FILE_TYPE = MACRO_DRAWING;
SET COLOR_WIRE YELLOW;
SET COLOR_PROP ORANGE;
SET COLOR_DOT WHITE;
SET COLOR_ARC YELLOW;
SET COLOR_BODY GREEN;
SET COLOR_NOTE PURPLE;
SET PROP_DISPLAY VALUE;
SET PAGE_NUMBER P9;
FORCEADD RESISTOR..1
(-10200 9900);
FORCEPROP 1 LAST $LOCATION R77
J 2
(-10400 9900);
DISPLAY 1.212766 (-10400 9900);
PAINT GREEN (-10400 9900);
FORCEPROP 0 LAST CDS_LOCATION R77
J 0
(-10000 10000);
DISPLAY 1.021277 (-10000 10000);
DISPLAY INVISIBLE (-10000 10000);
FORCEPROP 0 LAST $SEC 1
J 0
(-10000 10000);
DISPLAY 0.680851 (-10000 10000);
PAINT MONO (-10000 10000);
DISPLAY INVISIBLE (-10000 10000);
FORCEPROP 0 LAST CDS_SEC 1
J 0
(-10000 10000);
DISPLAY 1.021277 (-10000 10000);
DISPLAY INVISIBLE (-10000 10000);
FORCEPROP 0 LASTPIN (-10300 9900) $PN 1
J 2
(-10310 9910);
DISPLAY 0.680851 (-10310 9910);
PAINT MONO (-10310 9910);
FORCEPROP 0 LASTPIN (-10050 9900) $PN 2
J 0
(-10040 9910);
DISPLAY 0.680851 (-10040 9910);
PAINT MONO (-10040 9910);
FORCEPROP 1 LAST VALUE 33OHM
J 0
(-10000 9900);
DISPLAY 1.234043 (-10000 9900);
PAINT GREEN (-10000 9900);
FORCEPROP 0 LAST PACKAGE 0402
J 0
(-10250 9900);
DISPLAY 1.021277 (-10250 9900);
FORCEPROP 1 LAST PATH I11
J 0
(-10397 10005);
DISPLAY 1.212766 (-10397 10005);
PAINT GREEN (-10397 10005);
DISPLAY INVISIBLE (-10397 10005);
FORCEPROP 1 LAST TOLERANCE 1%
J 0
(-10397 10155);
DISPLAY 1.212766 (-10397 10155);
PAINT GREEN (-10397 10155);
DISPLAY INVISIBLE (-10397 10155);
FORCEPROP 1 LAST CLS_PN G155-133R0-01
J 0
(-10336 10100);
DISPLAY 1.212766 (-10336 10100);
PAINT GREEN (-10336 10100);
DISPLAY INVISIBLE (-10336 10100);
FORCEPROP 2 LAST SIGNAL_MODEL DEFAULT_RESISTOR_33OHM_2_1
J 0
(-10350 10100);
DISPLAY 1.021277 (-10350 10100);
DISPLAY INVISIBLE (-10350 10100);
FORCEPROP 1 LAST CDS_LMAN_SYM_OUTLINE -50,50,100,-50
J 0
(-10200 9900);
DISPLAY 0.468085 (-10200 9900);
PAINT GREEN (-10200 9900);
DISPLAY INVISIBLE (-10200 9900);
FORCEPROP 2 LAST CDS_LIB passive
J 0
(-10200 9900);
DISPLAY INVISIBLE (-10200 9900);
FORCEADD RESISTOR..1
(-10200 10000);
FORCEPROP 1 LAST $LOCATION R76
J 2
(-10400 10000);
DISPLAY 1.212766 (-10400 10000);
PAINT GREEN (-10400 10000);
FORCEPROP 0 LAST CDS_LOCATION R76
J 0
(-10000 10100);
DISPLAY 1.021277 (-10000 10100);
DISPLAY INVISIBLE (-10000 10100);
FORCEPROP 0 LAST $SEC 1
J 0
(-10000 10100);
DISPLAY 0.680851 (-10000 10100);
PAINT MONO (-10000 10100);
DISPLAY INVISIBLE (-10000 10100);
FORCEPROP 0 LAST CDS_SEC 1
J 0
(-10000 10100);
DISPLAY 1.021277 (-10000 10100);
DISPLAY INVISIBLE (-10000 10100);
FORCEPROP 0 LASTPIN (-10300 10000) $PN 1
J 2
(-10310 10010);
DISPLAY 0.680851 (-10310 10010);
PAINT MONO (-10310 10010);
FORCEPROP 0 LASTPIN (-10050 10000) $PN 2
J 0
(-10040 10010);
DISPLAY 0.680851 (-10040 10010);
PAINT MONO (-10040 10010);
FORCEPROP 1 LAST VALUE 33OHM
J 0
(-10000 10000);
DISPLAY 1.234043 (-10000 10000);
PAINT GREEN (-10000 10000);
FORCEPROP 0 LAST PACKAGE 0402
J 0
(-10250 10000);
DISPLAY 1.021277 (-10250 10000);
FORCEPROP 1 LAST PATH I12
J 0
(-10397 10105);
DISPLAY 1.212766 (-10397 10105);
PAINT GREEN (-10397 10105);
DISPLAY INVISIBLE (-10397 10105);
FORCEPROP 1 LAST TOLERANCE 1%
J 0
(-10397 10255);
DISPLAY 1.212766 (-10397 10255);
PAINT GREEN (-10397 10255);
DISPLAY INVISIBLE (-10397 10255);
FORCEPROP 1 LAST CLS_PN G155-133R0-01
J 0
(-10336 10200);
DISPLAY 1.212766 (-10336 10200);
PAINT GREEN (-10336 10200);
DISPLAY INVISIBLE (-10336 10200);
FORCEPROP 2 LAST SIGNAL_MODEL DEFAULT_RESISTOR_33OHM_2_1
J 0
(-10350 10200);
DISPLAY 1.021277 (-10350 10200);
DISPLAY INVISIBLE (-10350 10200);
FORCEPROP 1 LAST CDS_LMAN_SYM_OUTLINE -50,50,100,-50
J 0
(-10200 10000);
DISPLAY 0.468085 (-10200 10000);
PAINT GREEN (-10200 10000);
DISPLAY INVISIBLE (-10200 10000);
FORCEPROP 2 LAST CDS_LIB passive
J 0
(-10200 10000);
DISPLAY INVISIBLE (-10200 10000);
FORCEADD GND_SG..1
(-3650 10350);
FORCEPROP 3 LASTPIN (-3600 10400) SIG_NAME SG\g
J 0
(-3590 10410);
DISPLAY 0.659574 (-3590 10410);
PAINT MONO (-3590 10410);
DISPLAY INVISIBLE (-3590 10410);
FORCEPROP 1 LAST HDL_POWER SG
J 1
(-3595 10255);
DISPLAY 0.808511 (-3595 10255);
PAINT GREEN (-3595 10255);
FORCEPROP 1 LAST PATH I14
J 0
(-3615 10350);
DISPLAY 0.808511 (-3615 10350);
PAINT GREEN (-3615 10350);
DISPLAY INVISIBLE (-3615 10350);
FORCEPROP 1 LAST BODY_TYPE PLUMBING
J 0
(-3635 10335);
DISPLAY 0.808511 (-3635 10335);
PAINT GREEN (-3635 10335);
DISPLAY INVISIBLE (-3635 10335);
FORCEPROP 2 LAST CDS_LIB cls
J 0
(-3650 10350);
DISPLAY INVISIBLE (-3650 10350);
FORCEPROP 1 LAST CDS_LMAN_SYM_OUTLINE 0,0,100,-50
J 0
(-3650 10350);
DISPLAY 0.468085 (-3650 10350);
PAINT GREEN (-3650 10350);
DISPLAY INVISIBLE (-3650 10350);
FORCEADD XTAL_2..1
R 1
(-4700 10100);
FORCEPROP 1 LAST $LOCATION Y1
J 0
(-4400 10250);
DISPLAY 1.212766 (-4400 10250);
PAINT GREEN (-4400 10250);
FORCEPROP 0 LAST CDS_LOCATION Y1
R 1
J 0
(-5050 10100);
DISPLAY 1.021277 (-5050 10100);
DISPLAY INVISIBLE (-5050 10100);
FORCEPROP 0 LAST $SEC 1
R 1
J 0
(-5050 10100);
DISPLAY 0.680851 (-5050 10100);
PAINT MONO (-5050 10100);
DISPLAY INVISIBLE (-5050 10100);
FORCEPROP 0 LAST CDS_SEC 1
R 1
J 0
(-5050 10100);
DISPLAY 1.021277 (-5050 10100);
DISPLAY INVISIBLE (-5050 10100);
FORCEPROP 0 LASTPIN (-4600 10000) $PN 1
R 1
J 2
(-4610 9990);
DISPLAY 0.680851 (-4610 9990);
PAINT MONO (-4610 9990);
FORCEPROP 0 LASTPIN (-4600 10400) $PN 2
R 1
J 0
(-4610 10410);
DISPLAY 0.680851 (-4610 10410);
PAINT MONO (-4610 10410);
FORCEPROP 1 LAST CLS_PN G131-10075-01
J 0
(-4450 10150);
DISPLAY 0.978723 (-4450 10150);
PAINT GREEN (-4450 10150);
FORCEPROP 0 LAST PART_NUMBER 9H03200012
J 0
(-4450 10050);
DISPLAY 1.021277 (-4450 10050);
FORCEPROP 1 LAST PATH I16
R 1
J 0
(-4750 10050);
DISPLAY 1.212766 (-4750 10050);
PAINT GREEN (-4750 10050);
DISPLAY INVISIBLE (-4750 10050);
FORCEPROP 1 LAST CDS_LMAN_SYM_OUTLINE 0,0,200,-200
R 1
J 0
(-4700 10100);
DISPLAY 0.468085 (-4700 10100);
PAINT GREEN (-4700 10100);
DISPLAY INVISIBLE (-4700 10100);
FORCEPROP 2 LAST CDS_LIB clock
R 1
J 0
(-4700 10100);
DISPLAY INVISIBLE (-4700 10100);
FORCEADD CAPACITOR..2
R 1
(-4300 10450);
FORCEPROP 1 LAST $LOCATION C51
J 0
(-4500 10500);
DISPLAY 1.212766 (-4500 10500);
PAINT GREEN (-4500 10500);
FORCEPROP 0 LAST CDS_LOCATION C51
R 1
J 0
(-4450 10500);
DISPLAY 1.021277 (-4450 10500);
DISPLAY INVISIBLE (-4450 10500);
FORCEPROP 0 LAST $SEC 1
R 1
J 0
(-4450 10500);
DISPLAY 0.680851 (-4450 10500);
PAINT MONO (-4450 10500);
DISPLAY INVISIBLE (-4450 10500);
FORCEPROP 0 LAST CDS_SEC 1
R 1
J 0
(-4450 10500);
DISPLAY 1.021277 (-4450 10500);
DISPLAY INVISIBLE (-4450 10500);
FORCEPROP 0 LASTPIN (-4400 10450) $PN 1
J 2
(-4410 10460);
DISPLAY 0.680851 (-4410 10460);
PAINT MONO (-4410 10460);
FORCEPROP 0 LASTPIN (-4150 10450) $PN 2
J 0
(-4160 10460);
DISPLAY 0.680851 (-4160 10460);
PAINT MONO (-4160 10460);
FORCEPROP 0 LAST PACKAGE 0201
J 0
(-4250 10350);
DISPLAY 1.021277 (-4250 10350);
FORCEPROP 1 LAST VALUE 12PF
J 0
(-4200 10500);
DISPLAY 1.212766 (-4200 10500);
PAINT GREEN (-4200 10500);
FORCEPROP 0 LAST VOLTAGE 50V
J 0
(-4000 10350);
DISPLAY 1.021277 (-4000 10350);
FORCEPROP 1 LAST PATH I17
R 1
J 0
(-4350 10350);
DISPLAY 1.212766 (-4350 10350);
PAINT GREEN (-4350 10350);
DISPLAY INVISIBLE (-4350 10350);
FORCEPROP 1 LAST TOLERANCE 5%
R 1
J 0
(-4400 10300);
DISPLAY 1.212766 (-4400 10300);
PAINT GREEN (-4400 10300);
DISPLAY INVISIBLE (-4400 10300);
FORCEPROP 1 LAST CLS_PN G104-0A120-FJ
R 1
J 0
(-4350 10350);
DISPLAY 1.212766 (-4350 10350);
PAINT GREEN (-4350 10350);
DISPLAY INVISIBLE (-4350 10350);
FORCEPROP 2 LAST CDS_LIB passive
R 1
J 0
(-4300 10450);
DISPLAY INVISIBLE (-4300 10450);
FORCEPROP 1 LAST CDS_LMAN_SYM_OUTLINE -50,0,50,-50
R 1
J 0
(-4300 10450);
DISPLAY 0.468085 (-4300 10450);
PAINT GREEN (-4300 10450);
DISPLAY INVISIBLE (-4300 10450);
FORCEPROP 2 LASTPIN (-4400 10450) SIG_NAME UN$9$CAPACITOR$I17$1
R 1
J 0
(-4410 10460);
DISPLAY 0.659574 (-4410 10460);
PAINT MONO (-4410 10460);
DISPLAY INVISIBLE (-4410 10460);
FORCEADD VCC..1
(-11550 11100);
FORCEPROP 3 LASTPIN (-11500 11050) SIG_NAME XP3R3V_FPGA\g
J 0
(-11490 11060);
DISPLAY 0.659574 (-11490 11060);
PAINT MONO (-11490 11060);
DISPLAY INVISIBLE (-11490 11060);
FORCEPROP 0 LAST VOLTAGE 3.3V
J 0
(-11800 11250);
DISPLAY 1.021277 (-11800 11250);
DISPLAY BOTH (-11800 11250);
FORCEPROP 1 LAST HDL_POWER XP3R3V_FPGA
J 1
(-11495 11155);
DISPLAY 1.021277 (-11495 11155);
PAINT GREEN (-11495 11155);
FORCEPROP 2 LAST CDS_LIB cls
J 0
(-11550 11100);
DISPLAY INVISIBLE (-11550 11100);
FORCEPROP 1 LAST CDS_LMAN_SYM_OUTLINE -250,250,250,-250
J 0
(-11550 11100);
DISPLAY 0.468085 (-11550 11100);
PAINT GREEN (-11550 11100);
DISPLAY INVISIBLE (-11550 11100);
FORCEPROP 1 LAST PATH I18
J 0
(-11515 11190);
DISPLAY 0.808511 (-11515 11190);
PAINT GREEN (-11515 11190);
DISPLAY INVISIBLE (-11515 11190);
FORCEPROP 1 LAST BODY_TYPE PLUMBING
J 0
(-11595 11057);
DISPLAY 0.340426 (-11595 11057);
PAINT GREEN (-11595 11057);
DISPLAY INVISIBLE (-11595 11057);
FORCEADD GND_SG..1
R 2
(-8700 11200);
FORCEPROP 3 LASTPIN (-8750 11250) SIG_NAME SG\g
J 0
(-8740 11260);
DISPLAY 0.659574 (-8740 11260);
PAINT MONO (-8740 11260);
DISPLAY INVISIBLE (-8740 11260);
FORCEPROP 1 LAST HDL_POWER SG
J 1
(-8755 11105);
DISPLAY 0.808511 (-8755 11105);
PAINT GREEN (-8755 11105);
FORCEPROP 1 LAST PATH I19
J 2
(-8735 11200);
DISPLAY 0.808511 (-8735 11200);
PAINT GREEN (-8735 11200);
DISPLAY INVISIBLE (-8735 11200);
FORCEPROP 1 LAST BODY_TYPE PLUMBING
J 2
(-8715 11185);
DISPLAY 0.808511 (-8715 11185);
PAINT GREEN (-8715 11185);
DISPLAY INVISIBLE (-8715 11185);
FORCEPROP 2 LAST CDS_LIB cls
J 0
(-8700 11200);
DISPLAY INVISIBLE (-8700 11200);
FORCEPROP 1 LAST CDS_LMAN_SYM_OUTLINE 0,0,100,-50
J 2
(-8700 11200);
DISPLAY 0.468085 (-8700 11200);
PAINT GREEN (-8700 11200);
DISPLAY INVISIBLE (-8700 11200);
FORCEADD VCC..1
(-10300 12200);
FORCEPROP 3 LASTPIN (-10250 12150) SIG_NAME XP3R3V_FPGA\g
J 0
(-10240 12160);
DISPLAY 0.659574 (-10240 12160);
PAINT MONO (-10240 12160);
DISPLAY INVISIBLE (-10240 12160);
FORCEPROP 0 LAST VOLTAGE 3.3V
J 0
(-10550 12350);
DISPLAY 1.021277 (-10550 12350);
DISPLAY BOTH (-10550 12350);
FORCEPROP 1 LAST HDL_POWER XP3R3V_FPGA
J 1
(-10245 12255);
DISPLAY 1.021277 (-10245 12255);
PAINT GREEN (-10245 12255);
FORCEPROP 1 LAST PATH I20
J 0
(-10265 12290);
DISPLAY 0.808511 (-10265 12290);
PAINT GREEN (-10265 12290);
DISPLAY INVISIBLE (-10265 12290);
FORCEPROP 1 LAST BODY_TYPE PLUMBING
J 0
(-10345 12157);
DISPLAY 0.340426 (-10345 12157);
PAINT GREEN (-10345 12157);
DISPLAY INVISIBLE (-10345 12157);
FORCEPROP 2 LAST CDS_LIB cls
J 0
(-10300 12200);
DISPLAY INVISIBLE (-10300 12200);
FORCEPROP 1 LAST CDS_LMAN_SYM_OUTLINE -250,250,250,-250
J 0
(-10300 12200);
DISPLAY 0.468085 (-10300 12200);
PAINT GREEN (-10300 12200);
DISPLAY INVISIBLE (-10300 12200);
FORCEADD CAPACITOR..2
R 2
(-10250 11700);
FORCEPROP 1 LAST $LOCATION C279
J 2
(-9950 11600);
DISPLAY 1.212766 (-9950 11600);
PAINT GREEN (-9950 11600);
FORCEPROP 0 LAST CDS_LOCATION C279
J 0
(-9850 11800);
DISPLAY 1.021277 (-9850 11800);
DISPLAY INVISIBLE (-9850 11800);
FORCEPROP 0 LAST $SEC 1
J 0
(-9850 11800);
DISPLAY 0.680851 (-9850 11800);
PAINT MONO (-9850 11800);
DISPLAY INVISIBLE (-9850 11800);
FORCEPROP 0 LAST CDS_SEC 1
J 0
(-9850 11800);
DISPLAY 1.021277 (-9850 11800);
DISPLAY INVISIBLE (-9850 11800);
FORCEPROP 0 LASTPIN (-10250 11800) $PN 1
R 1
J 0
(-10260 11810);
DISPLAY 0.680851 (-10260 11810);
PAINT MONO (-10260 11810);
FORCEPROP 0 LASTPIN (-10250 11550) $PN 2
R 1
J 2
(-10260 11540);
DISPLAY 0.680851 (-10260 11540);
PAINT MONO (-10260 11540);
FORCEPROP 1 LAST VALUE 0.1UF
J 2
(-9850 11700);
DISPLAY 1.212766 (-9850 11700);
PAINT GREEN (-9850 11700);
FORCEPROP 0 LAST PACKAGE 0402
J 0
(-10150 11800);
DISPLAY 1.021277 (-10150 11800);
FORCEPROP 0 LAST VOLTAGE 25V
J 0
(-10100 11500);
DISPLAY 1.021277 (-10100 11500);
FORCEPROP 1 LAST PATH I21
J 2
(-10150 11750);
DISPLAY 1.212766 (-10150 11750);
PAINT GREEN (-10150 11750);
DISPLAY INVISIBLE (-10150 11750);
FORCEPROP 1 LAST TOLERANCE 10%
J 2
(-10100 11800);
DISPLAY 1.212766 (-10100 11800);
PAINT GREEN (-10100 11800);
DISPLAY INVISIBLE (-10100 11800);
FORCEPROP 1 LAST CLS_PN G105-0B104-EK
J 2
(-10150 11750);
DISPLAY 1.212766 (-10150 11750);
PAINT GREEN (-10150 11750);
DISPLAY INVISIBLE (-10150 11750);
FORCEPROP 1 LAST CDS_LMAN_SYM_OUTLINE -50,0,50,-50
J 2
(-10250 11700);
DISPLAY 0.468085 (-10250 11700);
PAINT GREEN (-10250 11700);
DISPLAY INVISIBLE (-10250 11700);
FORCEPROP 2 LAST CDS_LIB passive
J 0
(-10250 11700);
DISPLAY INVISIBLE (-10250 11700);
FORCEADD FERRITEBEAD..1
R 2
(-9650 12050);
FORCEPROP 1 LAST $LOCATION L19
J 0
(-10100 12100);
DISPLAY 1.212766 (-10100 12100);
PAINT GREEN (-10100 12100);
FORCEPROP 0 LAST CDS_LOCATION L19
J 0
(-9250 12150);
DISPLAY 1.021277 (-9250 12150);
DISPLAY INVISIBLE (-9250 12150);
FORCEPROP 0 LAST $SEC 1
J 0
(-9250 12150);
DISPLAY 0.680851 (-9250 12150);
PAINT MONO (-9250 12150);
DISPLAY INVISIBLE (-9250 12150);
FORCEPROP 0 LAST CDS_SEC 1
J 0
(-9250 12150);
DISPLAY 1.021277 (-9250 12150);
DISPLAY INVISIBLE (-9250 12150);
FORCEPROP 0 LASTPIN (-9550 12000) $PN 1
J 0
(-9540 12010);
DISPLAY 0.680851 (-9540 12010);
PAINT MONO (-9540 12010);
FORCEPROP 0 LASTPIN (-9950 12000) $PN 2
J 2
(-9960 12010);
DISPLAY 0.680851 (-9960 12010);
PAINT MONO (-9960 12010);
FORCEPROP 2 LAST DCR 1300MA 0.15OHM
J 2
(-9400 11900);
FORCEPROP 1 LAST VALUE 600OHM
J 2
(-9200 12050);
DISPLAY 1.212766 (-9200 12050);
PAINT GREEN (-9200 12050);
FORCEPROP 0 LAST PACKAGE 0603
J 0
(-9850 12100);
DISPLAY 1.021277 (-9850 12100);
FORCEPROP 1 LAST CDS_LMAN_SYM_OUTLINE 0,0,200,-100
J 2
(-9650 12050);
DISPLAY 0.468085 (-9650 12050);
PAINT GREEN (-9650 12050);
DISPLAY INVISIBLE (-9650 12050);
FORCEPROP 2 LAST CDS_LIB passive
J 0
(-9650 12050);
DISPLAY INVISIBLE (-9650 12050);
FORCEPROP 1 LAST CLS_PN G191-10097-01
J 0
(-9600 12100);
DISPLAY 1.212766 (-9600 12100);
PAINT GREEN (-9600 12100);
DISPLAY INVISIBLE (-9600 12100);
FORCEPROP 1 LAST PATH I22
J 0
(-9600 12100);
DISPLAY 1.212766 (-9600 12100);
PAINT GREEN (-9600 12100);
DISPLAY INVISIBLE (-9600 12100);
FORCEPROP 1 LAST TOLERANCE 25%
J 2
(-9550 12100);
DISPLAY 1.212766 (-9550 12100);
PAINT GREEN (-9550 12100);
DISPLAY INVISIBLE (-9550 12100);
FORCEADD CAPACITOR..2
R 2
(-9200 11700);
FORCEPROP 1 LAST $LOCATION C280
J 2
(-8900 11550);
DISPLAY 1.212766 (-8900 11550);
PAINT GREEN (-8900 11550);
FORCEPROP 0 LAST CDS_LOCATION C280
J 0
(-8900 11800);
DISPLAY 1.021277 (-8900 11800);
DISPLAY INVISIBLE (-8900 11800);
FORCEPROP 0 LAST $SEC 1
J 0
(-8900 11800);
DISPLAY 0.680851 (-8900 11800);
PAINT MONO (-8900 11800);
DISPLAY INVISIBLE (-8900 11800);
FORCEPROP 0 LAST CDS_SEC 1
J 0
(-8900 11800);
DISPLAY 1.021277 (-8900 11800);
DISPLAY INVISIBLE (-8900 11800);
FORCEPROP 0 LASTPIN (-9200 11800) $PN 1
R 1
J 0
(-9210 11810);
DISPLAY 0.680851 (-9210 11810);
PAINT MONO (-9210 11810);
FORCEPROP 0 LASTPIN (-9200 11550) $PN 2
R 1
J 2
(-9210 11540);
DISPLAY 0.680851 (-9210 11540);
PAINT MONO (-9210 11540);
FORCEPROP 0 LAST PACKAGE 0402
J 0
(-9100 11800);
DISPLAY 1.021277 (-9100 11800);
FORCEPROP 0 LAST VOLTAGE 6.3V
J 0
(-9100 11900);
DISPLAY 1.021277 (-9100 11900);
FORCEPROP 1 LAST VALUE 10UF
J 2
(-8900 11700);
DISPLAY 1.212766 (-8900 11700);
PAINT GREEN (-8900 11700);
FORCEPROP 1 LAST PATH I23
J 2
(-9100 11750);
DISPLAY 1.212766 (-9100 11750);
PAINT GREEN (-9100 11750);
DISPLAY INVISIBLE (-9100 11750);
FORCEPROP 1 LAST TOLERANCE 20%
J 2
(-9050 11800);
DISPLAY 1.212766 (-9050 11800);
PAINT GREEN (-9050 11800);
DISPLAY INVISIBLE (-9050 11800);
FORCEPROP 2 LAST CDS_LIB passive
J 0
(-9200 11700);
DISPLAY INVISIBLE (-9200 11700);
FORCEPROP 1 LAST CDS_LMAN_SYM_OUTLINE -50,0,50,-50
J 2
(-9200 11700);
DISPLAY 0.468085 (-9200 11700);
PAINT GREEN (-9200 11700);
DISPLAY INVISIBLE (-9200 11700);
FORCEPROP 1 LAST CLS_PN G105-0C106-BM
J 2
(-9100 11750);
DISPLAY 1.212766 (-9100 11750);
PAINT GREEN (-9100 11750);
DISPLAY INVISIBLE (-9100 11750);
FORCEADD CAPACITOR..2
R 2
(-8750 11700);
FORCEPROP 1 LAST $LOCATION C281
J 2
(-8400 11550);
DISPLAY 1.212766 (-8400 11550);
PAINT GREEN (-8400 11550);
FORCEPROP 0 LAST CDS_LOCATION C281
J 0
(-8350 11800);
DISPLAY 1.021277 (-8350 11800);
DISPLAY INVISIBLE (-8350 11800);
FORCEPROP 0 LAST $SEC 1
J 0
(-8350 11800);
DISPLAY 0.680851 (-8350 11800);
PAINT MONO (-8350 11800);
DISPLAY INVISIBLE (-8350 11800);
FORCEPROP 0 LAST CDS_SEC 1
J 0
(-8350 11800);
DISPLAY 1.021277 (-8350 11800);
DISPLAY INVISIBLE (-8350 11800);
FORCEPROP 0 LASTPIN (-8750 11800) $PN 1
R 1
J 0
(-8760 11810);
DISPLAY 0.680851 (-8760 11810);
PAINT MONO (-8760 11810);
FORCEPROP 0 LASTPIN (-8750 11550) $PN 2
R 1
J 2
(-8760 11540);
DISPLAY 0.680851 (-8760 11540);
PAINT MONO (-8760 11540);
FORCEPROP 1 LAST VALUE 0.1UF
J 2
(-8350 11700);
DISPLAY 1.212766 (-8350 11700);
PAINT GREEN (-8350 11700);
FORCEPROP 0 LAST PACKAGE 0402
J 0
(-8600 11800);
DISPLAY 1.021277 (-8600 11800);
FORCEPROP 0 LAST VOLTAGE 25V
J 0
(-8600 11900);
DISPLAY 1.021277 (-8600 11900);
FORCEPROP 1 LAST PATH I24
J 2
(-8650 11750);
DISPLAY 1.212766 (-8650 11750);
PAINT GREEN (-8650 11750);
DISPLAY INVISIBLE (-8650 11750);
FORCEPROP 1 LAST CDS_LMAN_SYM_OUTLINE -50,0,50,-50
J 2
(-8750 11700);
DISPLAY 0.468085 (-8750 11700);
PAINT GREEN (-8750 11700);
DISPLAY INVISIBLE (-8750 11700);
FORCEPROP 2 LAST CDS_LIB passive
J 0
(-8750 11700);
DISPLAY INVISIBLE (-8750 11700);
FORCEPROP 1 LAST CLS_PN G105-0B104-EK
J 2
(-8650 11750);
DISPLAY 1.212766 (-8650 11750);
PAINT GREEN (-8650 11750);
DISPLAY INVISIBLE (-8650 11750);
FORCEPROP 1 LAST TOLERANCE 10%
J 2
(-8600 11800);
DISPLAY 1.212766 (-8600 11800);
PAINT GREEN (-8600 11800);
DISPLAY INVISIBLE (-8600 11800);
FORCEADD BNO080_LGA_28..1
(-7500 10500);
FORCEPROP 2 LASTPIN (-7600 9200) SIG_NAME UN$9$BNO080LGA28$I29$HCS
J 0
(-7590 9210);
DISPLAY 0.659574 (-7590 9210);
PAINT MONO (-7590 9210);
DISPLAY INVISIBLE (-7590 9210);
FORCEPROP 1 LAST $LOCATION U29
J 0
(-7450 10600);
DISPLAY 1.212766 (-7450 10600);
PAINT GREEN (-7450 10600);
FORCEPROP 0 LAST CDS_LOCATION U29
J 0
(-7450 10900);
DISPLAY 1.021277 (-7450 10900);
DISPLAY INVISIBLE (-7450 10900);
FORCEPROP 0 LAST $SEC 1
J 0
(-7450 10900);
DISPLAY 0.680851 (-7450 10900);
PAINT MONO (-7450 10900);
DISPLAY INVISIBLE (-7450 10900);
FORCEPROP 0 LAST CDS_SEC 1
J 0
(-7450 10900);
DISPLAY 1.021277 (-7450 10900);
DISPLAY INVISIBLE (-7450 10900);
FORCEPROP 0 LASTPIN (-7600 9700) $PN 4
J 2
(-7610 9710);
DISPLAY 0.680851 (-7610 9710);
PAINT MONO (-7610 9710);
FORCEPROP 0 LASTPIN (-5650 10400) $PN 9
J 0
(-5640 10410);
DISPLAY 0.680851 (-5640 10410);
PAINT MONO (-5640 10410);
FORCEPROP 0 LASTPIN (-7600 9300) $PN 10
J 2
(-7610 9310);
DISPLAY 0.680851 (-7610 9310);
PAINT MONO (-7610 9310);
FORCEPROP 0 LASTPIN (-5650 9900) $PN 15
J 0
(-5640 9910);
DISPLAY 0.680851 (-5640 9910);
PAINT MONO (-5640 9910);
FORCEPROP 0 LASTPIN (-5650 10000) $PN 16
J 0
(-5640 10010);
DISPLAY 0.680851 (-5640 10010);
PAINT MONO (-5640 10010);
FORCEPROP 0 LASTPIN (-7600 9000) $PN 2
J 2
(-7610 9010);
DISPLAY 0.680851 (-7610 9010);
PAINT MONO (-7610 9010);
FORCEPROP 0 LASTPIN (-7600 8900) $PN 25
J 2
(-7610 8910);
DISPLAY 0.680851 (-7610 8910);
PAINT MONO (-7610 8910);
FORCEPROP 0 LASTPIN (-7600 9200) $PN 18
J 2
(-7610 9210);
DISPLAY 0.680851 (-7610 9210);
PAINT MONO (-7610 9210);
FORCEPROP 0 LASTPIN (-7600 9800) $PN 14
J 2
(-7610 9810);
DISPLAY 0.680851 (-7610 9810);
PAINT MONO (-7610 9810);
FORCEPROP 0 LASTPIN (-7600 9900) $PN 19
J 2
(-7610 9910);
DISPLAY 0.680851 (-7610 9910);
PAINT MONO (-7610 9910);
FORCEPROP 0 LASTPIN (-7600 10000) $PN 20
J 2
(-7610 10010);
DISPLAY 0.680851 (-7610 10010);
PAINT MONO (-7610 10010);
FORCEPROP 0 LASTPIN (-7600 9400) $PN 6
J 2
(-7610 9410);
DISPLAY 0.680851 (-7610 9410);
PAINT MONO (-7610 9410);
FORCEPROP 0 LASTPIN (-7600 9500) $PN 5
J 2
(-7610 9510);
DISPLAY 0.680851 (-7610 9510);
PAINT MONO (-7610 9510);
FORCEPROP 0 LASTPIN (-5650 9500) $PN 1
J 0
(-5640 9510);
DISPLAY 0.680851 (-5640 9510);
PAINT MONO (-5640 9510);
FORCEPROP 0 LASTPIN (-5650 9400) $PN 7
J 0
(-5640 9410);
DISPLAY 0.680851 (-5640 9410);
PAINT MONO (-5640 9410);
FORCEPROP 0 LASTPIN (-5650 9300) $PN 8
J 0
(-5640 9310);
DISPLAY 0.680851 (-5640 9310);
PAINT MONO (-5640 9310);
FORCEPROP 0 LASTPIN (-5650 9200) $PN 12
J 0
(-5640 9210);
DISPLAY 0.680851 (-5640 9210);
PAINT MONO (-5640 9210);
FORCEPROP 0 LASTPIN (-5650 9100) $PN 13
J 0
(-5640 9110);
DISPLAY 0.680851 (-5640 9110);
PAINT MONO (-5640 9110);
FORCEPROP 0 LASTPIN (-5650 9000) $PN 21
J 0
(-5640 9010);
DISPLAY 0.680851 (-5640 9010);
PAINT MONO (-5640 9010);
FORCEPROP 0 LASTPIN (-5650 8900) $PN 22
J 0
(-5640 8910);
DISPLAY 0.680851 (-5640 8910);
PAINT MONO (-5640 8910);
FORCEPROP 0 LASTPIN (-5650 8800) $PN 23
J 0
(-5640 8810);
DISPLAY 0.680851 (-5640 8810);
PAINT MONO (-5640 8810);
FORCEPROP 0 LASTPIN (-5650 8700) $PN 24
J 0
(-5640 8710);
DISPLAY 0.680851 (-5640 8710);
PAINT MONO (-5640 8710);
FORCEPROP 0 LASTPIN (-5650 9700) $PN 11
J 0
(-5640 9710);
DISPLAY 0.680851 (-5640 9710);
PAINT MONO (-5640 9710);
FORCEPROP 0 LASTPIN (-7600 10100) $PN 17
J 2
(-7610 10110);
DISPLAY 0.680851 (-7610 10110);
PAINT MONO (-7610 10110);
FORCEPROP 0 LASTPIN (-7600 10400) $PN 3
J 2
(-7610 10410);
DISPLAY 0.680851 (-7610 10410);
PAINT MONO (-7610 10410);
FORCEPROP 0 LASTPIN (-7600 10300) $PN 28
J 2
(-7610 10310);
DISPLAY 0.680851 (-7610 10310);
PAINT MONO (-7610 10310);
FORCEPROP 0 LASTPIN (-5650 10200) $PN 27
J 0
(-5640 10210);
DISPLAY 0.680851 (-5640 10210);
PAINT MONO (-5640 10210);
FORCEPROP 0 LASTPIN (-5650 10100) $PN 26
J 0
(-5640 10110);
DISPLAY 0.680851 (-5640 10110);
PAINT MONO (-5640 10110);
FORCEPROP 1 LAST CLS_PN A246-00002-FB
J 0
(-7450 10700);
DISPLAY 1.212766 (-7450 10700);
PAINT GREEN (-7450 10700);
FORCEPROP 1 LAST VALUE BNO085
J 0
(-7450 10800);
DISPLAY 1.212766 (-7450 10800);
PAINT GREEN (-7450 10800);
FORCEPROP 1 LAST PATH I29
J 0
(-7450 10550);
DISPLAY 1.212766 (-7450 10550);
PAINT GREEN (-7450 10550);
DISPLAY INVISIBLE (-7450 10550);
FORCEPROP 2 LAST CDS_LIB lsi
J 0
(-7500 10500);
DISPLAY INVISIBLE (-7500 10500);
FORCEPROP 1 LAST CDS_LMAN_SYM_OUTLINE 0,0,1750,-1900
J 0
(-7500 10500);
DISPLAY 0.468085 (-7500 10500);
PAINT GREEN (-7500 10500);
DISPLAY INVISIBLE (-7500 10500);
FORCEPROP 2 LASTPIN (-7600 9400) SIG_NAME UN$9$BNO080LGA28$I29$PS0
J 0
(-7590 9410);
DISPLAY 0.659574 (-7590 9410);
PAINT MONO (-7590 9410);
DISPLAY INVISIBLE (-7590 9410);
FORCEPROP 2 LASTPIN (-7600 9500) SIG_NAME UN$9$BNO080LGA28$I29$PS1
J 0
(-7590 9510);
DISPLAY 0.659574 (-7590 9510);
PAINT MONO (-7590 9510);
DISPLAY INVISIBLE (-7590 9510);
FORCEPROP 2 LASTPIN (-7600 9300) SIG_NAME UN$9$BNO080LGA28$I29$CLKSEL0
J 0
(-7590 9310);
DISPLAY 0.659574 (-7590 9310);
PAINT MONO (-7590 9310);
DISPLAY INVISIBLE (-7590 9310);
FORCEPROP 2 LASTPIN (-5650 10100) SIG_NAME UN$9$BNO080LGA28$I29$XOUT32
J 0
(-5640 10110);
DISPLAY 0.659574 (-5640 10110);
PAINT MONO (-5640 10110);
DISPLAY INVISIBLE (-5640 10110);
FORCEPROP 2 LASTPIN (-5650 10400) SIG_NAME UN$9$BNO080LGA28$I29$CAP
J 0
(-5640 10410);
DISPLAY 0.659574 (-5640 10410);
PAINT MONO (-5640 10410);
DISPLAY INVISIBLE (-5640 10410);
FORCEADD RESISTOR..1
(-10200 9800);
FORCEPROP 1 LAST $LOCATION R79
J 2
(-10400 9800);
DISPLAY 1.212766 (-10400 9800);
PAINT GREEN (-10400 9800);
FORCEPROP 0 LAST CDS_LOCATION R79
J 0
(-10000 9900);
DISPLAY 1.021277 (-10000 9900);
DISPLAY INVISIBLE (-10000 9900);
FORCEPROP 0 LAST $SEC 1
J 0
(-10000 9900);
DISPLAY 0.680851 (-10000 9900);
PAINT MONO (-10000 9900);
DISPLAY INVISIBLE (-10000 9900);
FORCEPROP 0 LAST CDS_SEC 1
J 0
(-10000 9900);
DISPLAY 1.021277 (-10000 9900);
DISPLAY INVISIBLE (-10000 9900);
FORCEPROP 0 LASTPIN (-10300 9800) $PN 1
J 2
(-10310 9810);
DISPLAY 0.680851 (-10310 9810);
PAINT MONO (-10310 9810);
FORCEPROP 0 LASTPIN (-10050 9800) $PN 2
J 0
(-10040 9810);
DISPLAY 0.680851 (-10040 9810);
PAINT MONO (-10040 9810);
FORCEPROP 1 LAST VALUE 33OHM
J 0
(-10000 9800);
DISPLAY 1.234043 (-10000 9800);
PAINT GREEN (-10000 9800);
FORCEPROP 0 LAST PACKAGE 0402
J 0
(-10250 9800);
DISPLAY 1.021277 (-10250 9800);
FORCEPROP 1 LAST PATH I31
J 0
(-10397 9905);
DISPLAY 1.212766 (-10397 9905);
PAINT GREEN (-10397 9905);
DISPLAY INVISIBLE (-10397 9905);
FORCEPROP 1 LAST TOLERANCE 1%
J 0
(-10397 10055);
DISPLAY 1.212766 (-10397 10055);
PAINT GREEN (-10397 10055);
DISPLAY INVISIBLE (-10397 10055);
FORCEPROP 1 LAST CLS_PN G155-133R0-01
J 0
(-10336 10000);
DISPLAY 1.212766 (-10336 10000);
PAINT GREEN (-10336 10000);
DISPLAY INVISIBLE (-10336 10000);
FORCEPROP 2 LAST SIGNAL_MODEL DEFAULT_RESISTOR_33OHM_2_1
J 0
(-10350 10000);
DISPLAY 1.021277 (-10350 10000);
DISPLAY INVISIBLE (-10350 10000);
FORCEPROP 1 LAST CDS_LMAN_SYM_OUTLINE -50,50,100,-50
J 0
(-10200 9800);
DISPLAY 0.468085 (-10200 9800);
PAINT GREEN (-10200 9800);
DISPLAY INVISIBLE (-10200 9800);
FORCEPROP 2 LAST CDS_LIB passive
J 0
(-10200 9800);
DISPLAY INVISIBLE (-10200 9800);
FORCEADD RESISTOR..1
(-10200 9700);
FORCEPROP 1 LAST $LOCATION R80
J 2
(-10400 9700);
DISPLAY 1.212766 (-10400 9700);
PAINT GREEN (-10400 9700);
FORCEPROP 0 LAST CDS_LOCATION R80
J 0
(-10000 9800);
DISPLAY 1.021277 (-10000 9800);
DISPLAY INVISIBLE (-10000 9800);
FORCEPROP 0 LAST $SEC 1
J 0
(-10000 9800);
DISPLAY 0.680851 (-10000 9800);
PAINT MONO (-10000 9800);
DISPLAY INVISIBLE (-10000 9800);
FORCEPROP 0 LAST CDS_SEC 1
J 0
(-10000 9800);
DISPLAY 1.021277 (-10000 9800);
DISPLAY INVISIBLE (-10000 9800);
FORCEPROP 0 LASTPIN (-10300 9700) $PN 1
J 2
(-10310 9710);
DISPLAY 0.680851 (-10310 9710);
PAINT MONO (-10310 9710);
FORCEPROP 0 LASTPIN (-10050 9700) $PN 2
J 0
(-10040 9710);
DISPLAY 0.680851 (-10040 9710);
PAINT MONO (-10040 9710);
FORCEPROP 0 LAST PACKAGE 0402
J 0
(-10250 9700);
DISPLAY 1.021277 (-10250 9700);
FORCEPROP 1 LAST VALUE 33OHM
J 0
(-10000 9700);
DISPLAY 1.234043 (-10000 9700);
PAINT GREEN (-10000 9700);
FORCEPROP 1 LAST PATH I32
J 0
(-10397 9805);
DISPLAY 1.212766 (-10397 9805);
PAINT GREEN (-10397 9805);
DISPLAY INVISIBLE (-10397 9805);
FORCEPROP 1 LAST TOLERANCE 1%
J 0
(-10397 9955);
DISPLAY 1.212766 (-10397 9955);
PAINT GREEN (-10397 9955);
DISPLAY INVISIBLE (-10397 9955);
FORCEPROP 1 LAST CLS_PN G155-133R0-01
J 0
(-10336 9900);
DISPLAY 1.212766 (-10336 9900);
PAINT GREEN (-10336 9900);
DISPLAY INVISIBLE (-10336 9900);
FORCEPROP 2 LAST SIGNAL_MODEL DEFAULT_RESISTOR_33OHM_2_1
J 0
(-10350 9900);
DISPLAY 1.021277 (-10350 9900);
DISPLAY INVISIBLE (-10350 9900);
FORCEPROP 2 LAST CDS_LIB passive
J 0
(-10200 9700);
DISPLAY INVISIBLE (-10200 9700);
FORCEPROP 1 LAST CDS_LMAN_SYM_OUTLINE -50,50,100,-50
J 0
(-10200 9700);
DISPLAY 0.468085 (-10200 9700);
PAINT GREEN (-10200 9700);
DISPLAY INVISIBLE (-10200 9700);
FORCEADD OFFPAGE_OUT..1
R 2
(-13000 9800);
FORCEPROP 2 LAST CDS_LIB cls
J 0
(-13000 9800);
DISPLAY INVISIBLE (-13000 9800);
FORCEPROP 1 LAST CDS_LMAN_SYM_OUTLINE -50,50,50,-50
J 2
(-13000 9800);
DISPLAY 0.468085 (-13000 9800);
PAINT GREEN (-13000 9800);
DISPLAY INVISIBLE (-13000 9800);
FORCEPROP 2 LAST PATH I34
J 0
(-13150 9850);
DISPLAY 1.021277 (-13150 9850);
DISPLAY INVISIBLE (-13150 9850);
FORCEPROP 1 LAST BODY_TYPE COMMENT
J 2
(-13010 9935);
DISPLAY 0.808511 (-13010 9935);
PAINT GREEN (-13010 9935);
DISPLAY INVISIBLE (-13010 9935);
FORCEPROP 1 LAST OFFPAGE TRUE
J 2
(-13010 9855);
DISPLAY 0.808511 (-13010 9855);
PAINT GREEN (-13010 9855);
DISPLAY INVISIBLE (-13010 9855);
FORCEPROP 2 LAST $XR0 12H5< 
J 0
(-13183 9800);
DISPLAY 0.638298 (-13183 9800);
PAINT MONO (-13183 9800);
FORCEADD OFFPAGE_IN..1
(-13000 9700);
FORCEPROP 2 LAST CDS_LIB cls
J 0
(-13000 9700);
DISPLAY INVISIBLE (-13000 9700);
FORCEPROP 1 LAST CDS_LMAN_SYM_OUTLINE -50,50,50,-50
J 0
(-13000 9700);
DISPLAY 0.468085 (-13000 9700);
PAINT GREEN (-13000 9700);
DISPLAY INVISIBLE (-13000 9700);
FORCEPROP 2 LAST PATH I35
J 0
(-13150 9750);
DISPLAY 1.021277 (-13150 9750);
DISPLAY INVISIBLE (-13150 9750);
FORCEPROP 1 LAST OFFPAGE TRUE
J 0
(-12990 9755);
DISPLAY 0.808511 (-12990 9755);
PAINT GREEN (-12990 9755);
DISPLAY INVISIBLE (-12990 9755);
FORCEPROP 1 LAST BODY_TYPE COMMENT
J 0
(-12990 9835);
DISPLAY 0.808511 (-12990 9835);
PAINT GREEN (-12990 9835);
DISPLAY INVISIBLE (-12990 9835);
FORCEPROP 2 LAST $XR0 12H5> 
J 0
(-13183 9700);
DISPLAY 0.638298 (-13183 9700);
PAINT MONO (-13183 9700);
FORCEADD RESISTOR..2
(-9050 10650);
FORCEPROP 1 LAST $LOCATION R304
J 0
(-9000 10500);
DISPLAY 1.212766 (-9000 10500);
PAINT GREEN (-9000 10500);
FORCEPROP 0 LAST CDS_LOCATION R304
J 0
(-9000 10750);
DISPLAY 1.021277 (-9000 10750);
DISPLAY INVISIBLE (-9000 10750);
FORCEPROP 0 LAST $SEC 1
J 0
(-9000 10750);
DISPLAY 0.680851 (-9000 10750);
PAINT MONO (-9000 10750);
DISPLAY INVISIBLE (-9000 10750);
FORCEPROP 0 LAST CDS_SEC 1
J 0
(-9000 10750);
DISPLAY 1.021277 (-9000 10750);
DISPLAY INVISIBLE (-9000 10750);
FORCEPROP 0 LASTPIN (-9050 10750) $PN 1
R 1
J 0
(-9060 10760);
DISPLAY 0.680851 (-9060 10760);
PAINT MONO (-9060 10760);
FORCEPROP 0 LASTPIN (-9050 10500) $PN 2
R 1
J 2
(-9060 10490);
DISPLAY 0.680851 (-9060 10490);
PAINT MONO (-9060 10490);
FORCEPROP 1 LAST VALUE 4.7KOHM
J 0
(-9000 10700);
DISPLAY 0.978723 (-9000 10700);
PAINT GREEN (-9000 10700);
FORCEPROP 0 LAST PACKAGE 0402
J 0
(-9000 10800);
DISPLAY 1.021277 (-9000 10800);
FORCEPROP 1 LAST PATH I37
J 0
(-9247 10755);
DISPLAY 1.212766 (-9247 10755);
PAINT GREEN (-9247 10755);
DISPLAY INVISIBLE (-9247 10755);
FORCEPROP 1 LAST TOLERANCE 1%
J 0
(-9247 10905);
DISPLAY 1.212766 (-9247 10905);
PAINT GREEN (-9247 10905);
DISPLAY INVISIBLE (-9247 10905);
FORCEPROP 2 LAST CDS_LIB passive
J 0
(-9050 10650);
DISPLAY INVISIBLE (-9050 10650);
FORCEPROP 1 LAST CDS_LMAN_SYM_OUTLINE -50,50,50,-100
J 0
(-9050 10650);
DISPLAY 0.468085 (-9050 10650);
PAINT GREEN (-9050 10650);
DISPLAY INVISIBLE (-9050 10650);
FORCEPROP 1 LAST CLS_PN G155-14701-01
J 0
(-9186 10850);
DISPLAY 1.212766 (-9186 10850);
PAINT GREEN (-9186 10850);
DISPLAY INVISIBLE (-9186 10850);
FORCEADD RESISTOR..2
(-10700 10700);
FORCEPROP 1 LAST LOCATION R289
J 0
(-10650 10550);
DISPLAY 1.212766 (-10650 10550);
PAINT GREEN (-10650 10550);
FORCEPROP 0 LAST $SEC 1
J 0
(-10650 10800);
DISPLAY 0.680851 (-10650 10800);
PAINT MONO (-10650 10800);
DISPLAY INVISIBLE (-10650 10800);
FORCEPROP 0 LAST CDS_SEC 1
J 0
(-10650 10800);
DISPLAY 1.021277 (-10650 10800);
DISPLAY INVISIBLE (-10650 10800);
FORCEPROP 0 LASTPIN (-10700 10800) $PN 1
R 1
J 0
(-10710 10810);
DISPLAY 0.680851 (-10710 10810);
PAINT MONO (-10710 10810);
FORCEPROP 0 LASTPIN (-10700 10550) $PN 2
R 1
J 2
(-10710 10540);
DISPLAY 0.680851 (-10710 10540);
PAINT MONO (-10710 10540);
FORCEPROP 1 LAST VALUE 4.7KOHM
J 0
(-10650 10750);
DISPLAY 0.978723 (-10650 10750);
PAINT GREEN (-10650 10750);
FORCEPROP 0 LAST PACKAGE 0402
J 0
(-10650 10850);
DISPLAY 1.021277 (-10650 10850);
FORCEPROP 1 LAST PATH I38
J 0
(-10897 10805);
DISPLAY 1.212766 (-10897 10805);
PAINT GREEN (-10897 10805);
DISPLAY INVISIBLE (-10897 10805);
FORCEPROP 1 LAST TOLERANCE 1%
J 0
(-10897 10955);
DISPLAY 1.212766 (-10897 10955);
PAINT GREEN (-10897 10955);
DISPLAY INVISIBLE (-10897 10955);
FORCEPROP 2 LAST CDS_LIB passive
J 0
(-10700 10700);
DISPLAY INVISIBLE (-10700 10700);
FORCEPROP 1 LAST CDS_LMAN_SYM_OUTLINE -50,50,50,-100
J 0
(-10700 10700);
DISPLAY 0.468085 (-10700 10700);
PAINT GREEN (-10700 10700);
DISPLAY INVISIBLE (-10700 10700);
FORCEPROP 1 LAST CLS_PN G155-14701-01
J 0
(-10836 10900);
DISPLAY 1.212766 (-10836 10900);
PAINT GREEN (-10836 10900);
DISPLAY INVISIBLE (-10836 10900);
FORCEADD OFFPAGE_IN..1
(-13000 9900);
FORCEPROP 2 LAST PATH I4
J 0
(-13150 9950);
DISPLAY 1.021277 (-13150 9950);
DISPLAY INVISIBLE (-13150 9950);
FORCEPROP 1 LAST OFFPAGE TRUE
J 0
(-12990 9955);
DISPLAY 0.808511 (-12990 9955);
PAINT GREEN (-12990 9955);
DISPLAY INVISIBLE (-12990 9955);
FORCEPROP 1 LAST BODY_TYPE COMMENT
J 0
(-12990 10035);
DISPLAY 0.808511 (-12990 10035);
PAINT GREEN (-12990 10035);
DISPLAY INVISIBLE (-12990 10035);
FORCEPROP 1 LAST CDS_LMAN_SYM_OUTLINE -50,50,50,-50
J 0
(-13000 9900);
DISPLAY 0.468085 (-13000 9900);
PAINT GREEN (-13000 9900);
DISPLAY INVISIBLE (-13000 9900);
FORCEPROP 2 LAST CDS_LIB cls
J 0
(-13000 9900);
DISPLAY INVISIBLE (-13000 9900);
FORCEPROP 2 LAST $XR0 16D12> 
J 0
(-13214 9900);
DISPLAY 0.638298 (-13214 9900);
PAINT MONO (-13214 9900);
FORCEADD RESISTOR..1
(-2450 9700);
FORCEPROP 1 LAST $LOCATION R78
J 2
(-2650 9700);
DISPLAY 1.212766 (-2650 9700);
PAINT GREEN (-2650 9700);
FORCEPROP 0 LAST CDS_LOCATION R78
J 0
(-2250 9800);
DISPLAY 1.021277 (-2250 9800);
DISPLAY INVISIBLE (-2250 9800);
FORCEPROP 0 LAST $SEC 1
J 0
(-2250 9800);
DISPLAY 0.680851 (-2250 9800);
PAINT MONO (-2250 9800);
DISPLAY INVISIBLE (-2250 9800);
FORCEPROP 0 LAST CDS_SEC 1
J 0
(-2250 9800);
DISPLAY 1.021277 (-2250 9800);
DISPLAY INVISIBLE (-2250 9800);
FORCEPROP 0 LASTPIN (-2550 9700) $PN 1
J 2
(-2560 9710);
DISPLAY 0.680851 (-2560 9710);
PAINT MONO (-2560 9710);
FORCEPROP 0 LASTPIN (-2300 9700) $PN 2
J 0
(-2290 9710);
DISPLAY 0.680851 (-2290 9710);
PAINT MONO (-2290 9710);
FORCEPROP 0 LAST PACKAGE 0402
J 0
(-2500 9750);
DISPLAY 1.021277 (-2500 9750);
FORCEPROP 1 LAST VALUE 33OHM
J 0
(-2250 9700);
DISPLAY 1.234043 (-2250 9700);
PAINT GREEN (-2250 9700);
FORCEPROP 1 LAST PATH I41
J 0
(-2647 9805);
DISPLAY 1.212766 (-2647 9805);
PAINT GREEN (-2647 9805);
DISPLAY INVISIBLE (-2647 9805);
FORCEPROP 1 LAST TOLERANCE 1%
J 0
(-2647 9955);
DISPLAY 1.212766 (-2647 9955);
PAINT GREEN (-2647 9955);
DISPLAY INVISIBLE (-2647 9955);
FORCEPROP 1 LAST CLS_PN G155-133R0-01
J 0
(-2586 9900);
DISPLAY 1.212766 (-2586 9900);
PAINT GREEN (-2586 9900);
DISPLAY INVISIBLE (-2586 9900);
FORCEPROP 2 LAST SIGNAL_MODEL DEFAULT_RESISTOR_33OHM_2_1
J 0
(-2600 9900);
DISPLAY 1.021277 (-2600 9900);
DISPLAY INVISIBLE (-2600 9900);
FORCEPROP 2 LAST CDS_LIB passive
J 0
(-2450 9700);
DISPLAY INVISIBLE (-2450 9700);
FORCEPROP 1 LAST CDS_LMAN_SYM_OUTLINE -50,50,100,-50
J 0
(-2450 9700);
DISPLAY 0.468085 (-2450 9700);
PAINT GREEN (-2450 9700);
DISPLAY INVISIBLE (-2450 9700);
FORCEADD OFFPAGE_IN..1
R 2
(-650 9700);
FORCEPROP 2 LAST CDS_LIB cls
J 2
(-650 9700);
DISPLAY INVISIBLE (-650 9700);
FORCEPROP 1 LAST CDS_LMAN_SYM_OUTLINE -50,50,50,-50
J 2
(-650 9700);
DISPLAY 0.468085 (-650 9700);
PAINT GREEN (-650 9700);
DISPLAY INVISIBLE (-650 9700);
FORCEPROP 2 LAST PATH I42
J 2
(-700 9800);
DISPLAY 1.021277 (-700 9800);
DISPLAY INVISIBLE (-700 9800);
FORCEPROP 1 LAST BODY_TYPE COMMENT
J 2
(-660 9835);
DISPLAY 0.808511 (-660 9835);
PAINT GREEN (-660 9835);
DISPLAY INVISIBLE (-660 9835);
FORCEPROP 1 LAST OFFPAGE TRUE
J 2
(-660 9755);
DISPLAY 0.808511 (-660 9755);
PAINT GREEN (-660 9755);
DISPLAY INVISIBLE (-660 9755);
FORCEPROP 2 LAST $XR0 12H5> 
J 0
(-595 9700);
DISPLAY 0.638298 (-595 9700);
PAINT MONO (-595 9700);
FORCEADD RESISTOR..1
R 5
(-4000 9350);
FORCEPROP 1 LAST $LOCATION R301
J 2
(-3750 9250);
DISPLAY 1.212766 (-3750 9250);
PAINT GREEN (-3750 9250);
FORCEPROP 0 LAST CDS_LOCATION R301
R 3
J 0
(-3900 9150);
DISPLAY 1.021277 (-3900 9150);
DISPLAY INVISIBLE (-3900 9150);
FORCEPROP 0 LAST $SEC 1
R 3
J 0
(-3900 9150);
DISPLAY 0.680851 (-3900 9150);
PAINT MONO (-3900 9150);
DISPLAY INVISIBLE (-3900 9150);
FORCEPROP 0 LAST CDS_SEC 1
R 3
J 0
(-3900 9150);
DISPLAY 1.021277 (-3900 9150);
DISPLAY INVISIBLE (-3900 9150);
FORCEPROP 0 LASTPIN (-4000 9450) $PN 1
R 3
J 2
(-3990 9460);
DISPLAY 0.680851 (-3990 9460);
PAINT MONO (-3990 9460);
FORCEPROP 0 LASTPIN (-4000 9200) $PN 2
R 3
J 0
(-3990 9190);
DISPLAY 0.680851 (-3990 9190);
PAINT MONO (-3990 9190);
FORCEPROP 0 LAST PACKAGE 0402
J 0
(-3950 9500);
DISPLAY 1.021277 (-3950 9500);
FORCEPROP 1 LAST VALUE 4.7KOHM
J 0
(-3950 9350);
DISPLAY 1.234043 (-3950 9350);
PAINT GREEN (-3950 9350);
FORCEPROP 0 LAST NO_ASSY TRUE
J 0
(-3900 9200);
DISPLAY 0.808511 (-3900 9200);
DISPLAY BOTH (-3900 9200);
FORCEPROP 1 LAST TOLERANCE 1%
R 3
J 0
(-3745 9547);
DISPLAY 1.212766 (-3745 9547);
PAINT GREEN (-3745 9547);
DISPLAY INVISIBLE (-3745 9547);
FORCEPROP 1 LAST CLS_PN G155-14701-01
R 3
J 0
(-3800 9486);
DISPLAY 1.212766 (-3800 9486);
PAINT GREEN (-3800 9486);
DISPLAY INVISIBLE (-3800 9486);
FORCEPROP 1 LAST PATH I43
R 3
J 0
(-3895 9547);
DISPLAY 1.212766 (-3895 9547);
PAINT GREEN (-3895 9547);
DISPLAY INVISIBLE (-3895 9547);
FORCEPROP 2 LAST CDS_LIB passive
R 3
J 0
(-4000 9350);
DISPLAY INVISIBLE (-4000 9350);
FORCEPROP 1 LAST CDS_LMAN_SYM_OUTLINE -50,50,100,-50
R 3
J 0
(-4000 9350);
DISPLAY 0.468085 (-4000 9350);
PAINT GREEN (-4000 9350);
DISPLAY INVISIBLE (-4000 9350);
FORCEADD RESISTOR..1
R 5
(-3100 10250);
FORCEPROP 1 LAST $LOCATION R291
J 2
(-2800 10150);
DISPLAY 1.212766 (-2800 10150);
PAINT GREEN (-2800 10150);
FORCEPROP 0 LAST CDS_LOCATION R291
J 0
(-3050 10350);
DISPLAY 1.021277 (-3050 10350);
DISPLAY INVISIBLE (-3050 10350);
FORCEPROP 0 LAST $SEC 1
J 0
(-3050 10350);
DISPLAY 0.680851 (-3050 10350);
PAINT MONO (-3050 10350);
DISPLAY INVISIBLE (-3050 10350);
FORCEPROP 0 LAST CDS_SEC 1
J 0
(-3050 10350);
DISPLAY 1.021277 (-3050 10350);
DISPLAY INVISIBLE (-3050 10350);
FORCEPROP 0 LASTPIN (-3100 10350) $PN 1
R 1
J 0
(-3110 10360);
DISPLAY 0.680851 (-3110 10360);
PAINT MONO (-3110 10360);
FORCEPROP 0 LASTPIN (-3100 10100) $PN 2
R 1
J 2
(-3110 10090);
DISPLAY 0.680851 (-3110 10090);
PAINT MONO (-3110 10090);
FORCEPROP 1 LAST VALUE 4.7KOHM
J 0
(-3050 10250);
DISPLAY 1.234043 (-3050 10250);
PAINT GREEN (-3050 10250);
FORCEPROP 0 LAST PACKAGE 0402
J 0
(-3050 10400);
DISPLAY 1.021277 (-3050 10400);
FORCEPROP 1 LAST PATH I44
R 3
J 0
(-2995 10447);
DISPLAY 1.212766 (-2995 10447);
PAINT GREEN (-2995 10447);
DISPLAY INVISIBLE (-2995 10447);
FORCEPROP 1 LAST TOLERANCE 1%
R 3
J 0
(-2845 10447);
DISPLAY 1.212766 (-2845 10447);
PAINT GREEN (-2845 10447);
DISPLAY INVISIBLE (-2845 10447);
FORCEPROP 2 LAST CDS_LIB passive
J 0
(-3100 10250);
DISPLAY INVISIBLE (-3100 10250);
FORCEPROP 1 LAST CDS_LMAN_SYM_OUTLINE -50,50,100,-50
R 3
J 0
(-3100 10250);
DISPLAY 0.468085 (-3100 10250);
PAINT GREEN (-3100 10250);
DISPLAY INVISIBLE (-3100 10250);
FORCEPROP 1 LAST CLS_PN G155-14701-01
R 3
J 0
(-2900 10386);
DISPLAY 1.212766 (-2900 10386);
PAINT GREEN (-2900 10386);
DISPLAY INVISIBLE (-2900 10386);
FORCEADD GND_SG..1
(-4050 8950);
FORCEPROP 3 LASTPIN (-4000 9000) SIG_NAME SG\g
J 0
(-3990 9010);
DISPLAY 0.659574 (-3990 9010);
PAINT MONO (-3990 9010);
DISPLAY INVISIBLE (-3990 9010);
FORCEPROP 1 LAST HDL_POWER SG
J 1
(-3995 8855);
DISPLAY 0.808511 (-3995 8855);
PAINT GREEN (-3995 8855);
FORCEPROP 1 LAST CDS_LMAN_SYM_OUTLINE 0,0,100,-50
J 0
(-4050 8950);
DISPLAY 0.468085 (-4050 8950);
PAINT GREEN (-4050 8950);
DISPLAY INVISIBLE (-4050 8950);
FORCEPROP 2 LAST CDS_LIB cls
J 0
(-4050 8950);
DISPLAY INVISIBLE (-4050 8950);
FORCEPROP 1 LAST BODY_TYPE PLUMBING
J 0
(-4035 8935);
DISPLAY 0.808511 (-4035 8935);
PAINT GREEN (-4035 8935);
DISPLAY INVISIBLE (-4035 8935);
FORCEPROP 1 LAST PATH I45
J 0
(-4015 8950);
DISPLAY 0.808511 (-4015 8950);
PAINT GREEN (-4015 8950);
DISPLAY INVISIBLE (-4015 8950);
FORCEADD VCC..1
(-3150 10750);
FORCEPROP 3 LASTPIN (-3100 10700) SIG_NAME XP3R3V_FPGA\g
J 0
(-3090 10710);
DISPLAY 0.659574 (-3090 10710);
PAINT MONO (-3090 10710);
DISPLAY INVISIBLE (-3090 10710);
FORCEPROP 0 LAST VOLTAGE 3.3V
J 0
(-3400 10900);
DISPLAY 1.021277 (-3400 10900);
DISPLAY BOTH (-3400 10900);
FORCEPROP 1 LAST HDL_POWER XP3R3V_FPGA
J 1
(-3095 10805);
DISPLAY 1.021277 (-3095 10805);
PAINT GREEN (-3095 10805);
FORCEPROP 2 LAST CDS_LIB cls
J 0
(-3150 10750);
DISPLAY INVISIBLE (-3150 10750);
FORCEPROP 1 LAST CDS_LMAN_SYM_OUTLINE -250,250,250,-250
J 0
(-3150 10750);
DISPLAY 0.468085 (-3150 10750);
PAINT GREEN (-3150 10750);
DISPLAY INVISIBLE (-3150 10750);
FORCEPROP 1 LAST BODY_TYPE PLUMBING
J 0
(-3195 10707);
DISPLAY 0.340426 (-3195 10707);
PAINT GREEN (-3195 10707);
DISPLAY INVISIBLE (-3195 10707);
FORCEPROP 1 LAST PATH I46
J 0
(-3115 10840);
DISPLAY 0.808511 (-3115 10840);
PAINT GREEN (-3115 10840);
DISPLAY INVISIBLE (-3115 10840);
FORCEADD RESISTOR..2
(-8400 9050);
FORCEPROP 1 LAST $LOCATION R307
J 0
(-8350 8900);
DISPLAY 1.212766 (-8350 8900);
PAINT GREEN (-8350 8900);
FORCEPROP 0 LAST CDS_LOCATION R307
J 0
(-8350 9200);
DISPLAY 1.021277 (-8350 9200);
DISPLAY INVISIBLE (-8350 9200);
FORCEPROP 0 LAST $SEC 1
J 0
(-8350 9200);
DISPLAY 0.680851 (-8350 9200);
PAINT MONO (-8350 9200);
DISPLAY INVISIBLE (-8350 9200);
FORCEPROP 0 LAST CDS_SEC 1
J 0
(-8350 9200);
DISPLAY 1.021277 (-8350 9200);
DISPLAY INVISIBLE (-8350 9200);
FORCEPROP 0 LASTPIN (-8400 9150) $PN 1
R 1
J 0
(-8410 9160);
DISPLAY 0.680851 (-8410 9160);
PAINT MONO (-8410 9160);
FORCEPROP 0 LASTPIN (-8400 8900) $PN 2
R 1
J 2
(-8410 8890);
DISPLAY 0.680851 (-8410 8890);
PAINT MONO (-8410 8890);
FORCEPROP 1 LAST VALUE 1KOHM
J 0
(-8350 9100);
DISPLAY 1.212766 (-8350 9100);
PAINT GREEN (-8350 9100);
FORCEPROP 0 LAST PACKAGE 0402
J 0
(-8350 9250);
DISPLAY 1.021277 (-8350 9250);
FORCEPROP 1 LAST CLS_PN G155-11001-01
J 0
(-8536 9250);
DISPLAY 1.212766 (-8536 9250);
PAINT GREEN (-8536 9250);
DISPLAY INVISIBLE (-8536 9250);
FORCEPROP 1 LAST TOLERANCE 1%
J 0
(-8597 9305);
DISPLAY 1.212766 (-8597 9305);
PAINT GREEN (-8597 9305);
DISPLAY INVISIBLE (-8597 9305);
FORCEPROP 1 LAST PATH I47
J 0
(-8597 9155);
DISPLAY 1.212766 (-8597 9155);
PAINT GREEN (-8597 9155);
DISPLAY INVISIBLE (-8597 9155);
FORCEPROP 1 LAST CDS_LMAN_SYM_OUTLINE -50,50,50,-100
J 0
(-8400 9050);
DISPLAY 0.468085 (-8400 9050);
PAINT GREEN (-8400 9050);
DISPLAY INVISIBLE (-8400 9050);
FORCEPROP 2 LAST CDS_LIB passive
J 0
(-8400 9050);
DISPLAY INVISIBLE (-8400 9050);
FORCEADD GND_SG..1
(-7850 8450);
FORCEPROP 3 LASTPIN (-7800 8500) SIG_NAME SG\g
J 0
(-7790 8510);
DISPLAY 0.659574 (-7790 8510);
PAINT MONO (-7790 8510);
DISPLAY INVISIBLE (-7790 8510);
FORCEPROP 1 LAST HDL_POWER SG
J 1
(-7795 8355);
DISPLAY 0.808511 (-7795 8355);
PAINT GREEN (-7795 8355);
FORCEPROP 1 LAST PATH I48
J 0
(-7815 8450);
DISPLAY 0.808511 (-7815 8450);
PAINT GREEN (-7815 8450);
DISPLAY INVISIBLE (-7815 8450);
FORCEPROP 1 LAST BODY_TYPE PLUMBING
J 0
(-7835 8435);
DISPLAY 0.808511 (-7835 8435);
PAINT GREEN (-7835 8435);
DISPLAY INVISIBLE (-7835 8435);
FORCEPROP 2 LAST CDS_LIB cls
J 0
(-7850 8450);
DISPLAY INVISIBLE (-7850 8450);
FORCEPROP 1 LAST CDS_LMAN_SYM_OUTLINE 0,0,100,-50
J 0
(-7850 8450);
DISPLAY 0.468085 (-7850 8450);
PAINT GREEN (-7850 8450);
DISPLAY INVISIBLE (-7850 8450);
FORCEADD RESISTOR..2
(-8750 9050);
FORCEPROP 1 LAST $LOCATION R305
J 0
(-8700 8900);
DISPLAY 1.212766 (-8700 8900);
PAINT GREEN (-8700 8900);
FORCEPROP 0 LAST CDS_LOCATION R305
J 0
(-8700 9200);
DISPLAY 1.021277 (-8700 9200);
DISPLAY INVISIBLE (-8700 9200);
FORCEPROP 0 LAST $SEC 1
J 0
(-8700 9200);
DISPLAY 0.680851 (-8700 9200);
PAINT MONO (-8700 9200);
DISPLAY INVISIBLE (-8700 9200);
FORCEPROP 0 LAST CDS_SEC 1
J 0
(-8700 9200);
DISPLAY 1.021277 (-8700 9200);
DISPLAY INVISIBLE (-8700 9200);
FORCEPROP 0 LASTPIN (-8750 9150) $PN 1
R 1
J 0
(-8760 9160);
DISPLAY 0.680851 (-8760 9160);
PAINT MONO (-8760 9160);
FORCEPROP 0 LASTPIN (-8750 8900) $PN 2
R 1
J 2
(-8760 8890);
DISPLAY 0.680851 (-8760 8890);
PAINT MONO (-8760 8890);
FORCEPROP 1 LAST VALUE 1KOHM
J 0
(-8700 9100);
DISPLAY 1.212766 (-8700 9100);
PAINT GREEN (-8700 9100);
FORCEPROP 0 LAST PACKAGE 0402
J 0
(-8700 9250);
DISPLAY 1.021277 (-8700 9250);
FORCEPROP 1 LAST PATH I49
J 0
(-8947 9155);
DISPLAY 1.212766 (-8947 9155);
PAINT GREEN (-8947 9155);
DISPLAY INVISIBLE (-8947 9155);
FORCEPROP 1 LAST TOLERANCE 1%
J 0
(-8947 9305);
DISPLAY 1.212766 (-8947 9305);
PAINT GREEN (-8947 9305);
DISPLAY INVISIBLE (-8947 9305);
FORCEPROP 2 LAST CDS_LIB passive
J 0
(-8750 9050);
DISPLAY INVISIBLE (-8750 9050);
FORCEPROP 1 LAST CDS_LMAN_SYM_OUTLINE -50,50,50,-100
J 0
(-8750 9050);
DISPLAY 0.468085 (-8750 9050);
PAINT GREEN (-8750 9050);
DISPLAY INVISIBLE (-8750 9050);
FORCEPROP 1 LAST CLS_PN G155-11001-01
J 0
(-8886 9250);
DISPLAY 1.212766 (-8886 9250);
PAINT GREEN (-8886 9250);
DISPLAY INVISIBLE (-8886 9250);
FORCEADD OFFPAGE_BI..1
R 2
(-13000 10000);
FORCEPROP 2 LAST PATH I5
J 0
(-13200 10050);
DISPLAY 1.021277 (-13200 10050);
DISPLAY INVISIBLE (-13200 10050);
FORCEPROP 1 LAST OFFPAGE TRUE
J 2
(-13010 10055);
DISPLAY 0.808511 (-13010 10055);
PAINT GREEN (-13010 10055);
DISPLAY INVISIBLE (-13010 10055);
FORCEPROP 1 LAST BODY_TYPE COMMENT
J 2
(-13010 10135);
DISPLAY 0.808511 (-13010 10135);
PAINT GREEN (-13010 10135);
DISPLAY INVISIBLE (-13010 10135);
FORCEPROP 1 LAST CDS_LMAN_SYM_OUTLINE -50,50,50,-50
J 2
(-13000 10000);
DISPLAY 0.468085 (-13000 10000);
PAINT GREEN (-13000 10000);
DISPLAY INVISIBLE (-13000 10000);
FORCEPROP 2 LAST CDS_LIB cls
J 0
(-13000 10000);
DISPLAY INVISIBLE (-13000 10000);
FORCEPROP 2 LAST $XR0 16D12<> 
J 0
(-13250 10000);
DISPLAY 0.638298 (-13250 10000);
PAINT MONO (-13250 10000);
FORCEADD RESISTOR..2
(-9100 9050);
FORCEPROP 1 LAST $LOCATION R303
J 0
(-9050 8900);
DISPLAY 1.212766 (-9050 8900);
PAINT GREEN (-9050 8900);
FORCEPROP 0 LAST CDS_LOCATION R303
J 0
(-9050 9200);
DISPLAY 1.021277 (-9050 9200);
DISPLAY INVISIBLE (-9050 9200);
FORCEPROP 0 LAST $SEC 1
J 0
(-9050 9200);
DISPLAY 0.680851 (-9050 9200);
PAINT MONO (-9050 9200);
DISPLAY INVISIBLE (-9050 9200);
FORCEPROP 0 LAST CDS_SEC 1
J 0
(-9050 9200);
DISPLAY 1.021277 (-9050 9200);
DISPLAY INVISIBLE (-9050 9200);
FORCEPROP 0 LASTPIN (-9100 9150) $PN 1
R 1
J 0
(-9110 9160);
DISPLAY 0.680851 (-9110 9160);
PAINT MONO (-9110 9160);
FORCEPROP 0 LASTPIN (-9100 8900) $PN 2
R 1
J 2
(-9110 8890);
DISPLAY 0.680851 (-9110 8890);
PAINT MONO (-9110 8890);
FORCEPROP 1 LAST VALUE 1KOHM
J 0
(-9050 9100);
DISPLAY 1.212766 (-9050 9100);
PAINT GREEN (-9050 9100);
FORCEPROP 0 LAST PACKAGE 0402
J 0
(-9050 9250);
DISPLAY 1.021277 (-9050 9250);
FORCEPROP 1 LAST PATH I50
J 0
(-9297 9155);
DISPLAY 1.212766 (-9297 9155);
PAINT GREEN (-9297 9155);
DISPLAY INVISIBLE (-9297 9155);
FORCEPROP 1 LAST TOLERANCE 1%
J 0
(-9297 9305);
DISPLAY 1.212766 (-9297 9305);
PAINT GREEN (-9297 9305);
DISPLAY INVISIBLE (-9297 9305);
FORCEPROP 1 LAST CLS_PN G155-11001-01
J 0
(-9236 9250);
DISPLAY 1.212766 (-9236 9250);
PAINT GREEN (-9236 9250);
DISPLAY INVISIBLE (-9236 9250);
FORCEPROP 2 LAST CDS_LIB passive
J 0
(-9100 9050);
DISPLAY INVISIBLE (-9100 9050);
FORCEPROP 1 LAST CDS_LMAN_SYM_OUTLINE -50,50,50,-100
J 0
(-9100 9050);
DISPLAY 0.468085 (-9100 9050);
PAINT GREEN (-9100 9050);
DISPLAY INVISIBLE (-9100 9050);
FORCEADD RESISTOR..2
(-9450 10650);
FORCEPROP 1 LAST LOCATION R290
J 0
(-9400 10500);
DISPLAY 1.212766 (-9400 10500);
PAINT GREEN (-9400 10500);
FORCEPROP 0 LAST $SEC 1
J 0
(-9400 10750);
DISPLAY 0.680851 (-9400 10750);
PAINT MONO (-9400 10750);
DISPLAY INVISIBLE (-9400 10750);
FORCEPROP 0 LAST CDS_SEC 1
J 0
(-9400 10750);
DISPLAY 1.021277 (-9400 10750);
DISPLAY INVISIBLE (-9400 10750);
FORCEPROP 0 LASTPIN (-9450 10750) $PN 1
R 1
J 0
(-9460 10760);
DISPLAY 0.680851 (-9460 10760);
PAINT MONO (-9460 10760);
FORCEPROP 0 LASTPIN (-9450 10500) $PN 2
R 1
J 2
(-9460 10490);
DISPLAY 0.680851 (-9460 10490);
PAINT MONO (-9460 10490);
FORCEPROP 1 LAST VALUE 4.7KOHM
J 0
(-9400 10700);
DISPLAY 0.978723 (-9400 10700);
PAINT GREEN (-9400 10700);
FORCEPROP 0 LAST PACKAGE 0402
J 0
(-9400 10800);
DISPLAY 1.021277 (-9400 10800);
FORCEPROP 0 LAST NO_ASSY TRUE
J 0
(-9900 10600);
DISPLAY 0.808511 (-9900 10600);
DISPLAY BOTH (-9900 10600);
FORCEPROP 1 LAST PATH I51
J 0
(-9647 10755);
DISPLAY 1.212766 (-9647 10755);
PAINT GREEN (-9647 10755);
DISPLAY INVISIBLE (-9647 10755);
FORCEPROP 1 LAST TOLERANCE 1%
J 0
(-9647 10905);
DISPLAY 1.212766 (-9647 10905);
PAINT GREEN (-9647 10905);
DISPLAY INVISIBLE (-9647 10905);
FORCEPROP 1 LAST CLS_PN G155-14701-01
J 0
(-9586 10850);
DISPLAY 1.212766 (-9586 10850);
PAINT GREEN (-9586 10850);
DISPLAY INVISIBLE (-9586 10850);
FORCEPROP 1 LAST CDS_LMAN_SYM_OUTLINE -50,50,50,-100
J 0
(-9450 10650);
DISPLAY 0.468085 (-9450 10650);
PAINT GREEN (-9450 10650);
DISPLAY INVISIBLE (-9450 10650);
FORCEPROP 2 LAST CDS_LIB passive
J 0
(-9450 10650);
DISPLAY INVISIBLE (-9450 10650);
FORCEADD RESISTOR..2
(-9450 9050);
FORCEPROP 1 LAST $LOCATION R302
J 0
(-9400 8900);
DISPLAY 1.212766 (-9400 8900);
PAINT GREEN (-9400 8900);
FORCEPROP 0 LAST CDS_LOCATION R302
J 0
(-9400 9200);
DISPLAY 1.021277 (-9400 9200);
DISPLAY INVISIBLE (-9400 9200);
FORCEPROP 0 LAST $SEC 1
J 0
(-9400 9200);
DISPLAY 0.680851 (-9400 9200);
PAINT MONO (-9400 9200);
DISPLAY INVISIBLE (-9400 9200);
FORCEPROP 0 LAST CDS_SEC 1
J 0
(-9400 9200);
DISPLAY 1.021277 (-9400 9200);
DISPLAY INVISIBLE (-9400 9200);
FORCEPROP 0 LASTPIN (-9450 9150) $PN 1
R 1
J 0
(-9460 9160);
DISPLAY 0.680851 (-9460 9160);
PAINT MONO (-9460 9160);
FORCEPROP 0 LASTPIN (-9450 8900) $PN 2
R 1
J 2
(-9460 8890);
DISPLAY 0.680851 (-9460 8890);
PAINT MONO (-9460 8890);
FORCEPROP 1 LAST VALUE 1KOHM
J 0
(-9400 9100);
DISPLAY 1.212766 (-9400 9100);
PAINT GREEN (-9400 9100);
FORCEPROP 0 LAST PACKAGE 0402
J 0
(-9400 9250);
DISPLAY 1.021277 (-9400 9250);
FORCEPROP 1 LAST PATH I52
J 0
(-9647 9155);
DISPLAY 1.212766 (-9647 9155);
PAINT GREEN (-9647 9155);
DISPLAY INVISIBLE (-9647 9155);
FORCEPROP 1 LAST TOLERANCE 1%
J 0
(-9647 9305);
DISPLAY 1.212766 (-9647 9305);
PAINT GREEN (-9647 9305);
DISPLAY INVISIBLE (-9647 9305);
FORCEPROP 1 LAST CLS_PN G155-11001-01
J 0
(-9586 9250);
DISPLAY 1.212766 (-9586 9250);
PAINT GREEN (-9586 9250);
DISPLAY INVISIBLE (-9586 9250);
FORCEPROP 1 LAST CDS_LMAN_SYM_OUTLINE -50,50,50,-100
J 0
(-9450 9050);
DISPLAY 0.468085 (-9450 9050);
PAINT GREEN (-9450 9050);
DISPLAY INVISIBLE (-9450 9050);
FORCEPROP 2 LAST CDS_LIB passive
J 0
(-9450 9050);
DISPLAY INVISIBLE (-9450 9050);
FORCEADD CAPACITOR..2
R 1
(-4800 10700);
FORCEPROP 1 LAST $LOCATION C285
J 0
(-5100 10750);
DISPLAY 1.212766 (-5100 10750);
PAINT GREEN (-5100 10750);
FORCEPROP 0 LAST CDS_LOCATION C285
R 1
J 0
(-5000 10750);
DISPLAY 1.021277 (-5000 10750);
DISPLAY INVISIBLE (-5000 10750);
FORCEPROP 0 LAST $SEC 1
R 1
J 0
(-5000 10750);
DISPLAY 0.680851 (-5000 10750);
PAINT MONO (-5000 10750);
DISPLAY INVISIBLE (-5000 10750);
FORCEPROP 0 LAST CDS_SEC 1
R 1
J 0
(-5000 10750);
DISPLAY 1.021277 (-5000 10750);
DISPLAY INVISIBLE (-5000 10750);
FORCEPROP 0 LASTPIN (-4900 10700) $PN 1
J 2
(-4910 10690);
DISPLAY 0.680851 (-4910 10690);
PAINT MONO (-4910 10690);
FORCEPROP 0 LASTPIN (-4650 10700) $PN 2
J 0
(-4640 10690);
DISPLAY 0.680851 (-4640 10690);
PAINT MONO (-4640 10690);
FORCEPROP 1 LAST VALUE 0.1UF
J 0
(-4650 10750);
DISPLAY 1.212766 (-4650 10750);
PAINT GREEN (-4650 10750);
FORCEPROP 0 LAST VOLTAGE 10V
J 0
(-4850 10800);
DISPLAY 1.021277 (-4850 10800);
FORCEPROP 0 LAST PACKAGE 0402
J 0
(-4850 10600);
DISPLAY 1.021277 (-4850 10600);
FORCEPROP 2 LAST CDS_LIB passive
R 1
J 0
(-4800 10700);
DISPLAY INVISIBLE (-4800 10700);
FORCEPROP 1 LAST CDS_LMAN_SYM_OUTLINE -50,0,50,-50
R 1
J 0
(-4800 10700);
DISPLAY 0.468085 (-4800 10700);
PAINT GREEN (-4800 10700);
DISPLAY INVISIBLE (-4800 10700);
FORCEPROP 1 LAST CLS_PN G105-0B104-CK
R 1
J 0
(-4850 10600);
DISPLAY 1.212766 (-4850 10600);
PAINT GREEN (-4850 10600);
DISPLAY INVISIBLE (-4850 10600);
FORCEPROP 1 LAST TOLERANCE 10%
R 1
J 0
(-4900 10550);
DISPLAY 1.212766 (-4900 10550);
PAINT GREEN (-4900 10550);
DISPLAY INVISIBLE (-4900 10550);
FORCEPROP 1 LAST PATH I53
R 1
J 0
(-4850 10600);
DISPLAY 1.212766 (-4850 10600);
PAINT GREEN (-4850 10600);
DISPLAY INVISIBLE (-4850 10600);
FORCEADD CAPACITOR..2
R 1
(-4300 9900);
FORCEPROP 1 LAST LOCATION C47
J 0
(-4500 9950);
DISPLAY 1.212766 (-4500 9950);
PAINT GREEN (-4500 9950);
FORCEPROP 0 LAST $SEC 1
R 1
J 0
(-4450 9950);
DISPLAY 0.680851 (-4450 9950);
PAINT MONO (-4450 9950);
DISPLAY INVISIBLE (-4450 9950);
FORCEPROP 0 LAST CDS_SEC 1
R 1
J 0
(-4450 9950);
DISPLAY 1.021277 (-4450 9950);
DISPLAY INVISIBLE (-4450 9950);
FORCEPROP 0 LASTPIN (-4400 9900) $PN 1
J 2
(-4410 9910);
DISPLAY 0.680851 (-4410 9910);
PAINT MONO (-4410 9910);
FORCEPROP 0 LASTPIN (-4150 9900) $PN 2
J 0
(-4160 9910);
DISPLAY 0.680851 (-4160 9910);
PAINT MONO (-4160 9910);
FORCEPROP 1 LAST VALUE 12PF
J 0
(-4200 9950);
DISPLAY 1.212766 (-4200 9950);
PAINT GREEN (-4200 9950);
FORCEPROP 0 LAST PACKAGE 0201
J 0
(-4200 9850);
DISPLAY 1.021277 (-4200 9850);
FORCEPROP 0 LAST VOLTAGE 50V
J 0
(-3950 9850);
DISPLAY 1.021277 (-3950 9850);
FORCEPROP 1 LAST PATH I54
R 1
J 0
(-4350 9800);
DISPLAY 1.212766 (-4350 9800);
PAINT GREEN (-4350 9800);
DISPLAY INVISIBLE (-4350 9800);
FORCEPROP 1 LAST TOLERANCE 5%
R 1
J 0
(-4400 9750);
DISPLAY 1.212766 (-4400 9750);
PAINT GREEN (-4400 9750);
DISPLAY INVISIBLE (-4400 9750);
FORCEPROP 1 LAST CLS_PN G104-0A120-FJ
R 1
J 0
(-4350 9800);
DISPLAY 1.212766 (-4350 9800);
PAINT GREEN (-4350 9800);
DISPLAY INVISIBLE (-4350 9800);
FORCEPROP 2 LAST CDS_LIB passive
R 1
J 0
(-4300 9900);
DISPLAY INVISIBLE (-4300 9900);
FORCEPROP 1 LAST CDS_LMAN_SYM_OUTLINE -50,0,50,-50
R 1
J 0
(-4300 9900);
DISPLAY 0.468085 (-4300 9900);
PAINT GREEN (-4300 9900);
DISPLAY INVISIBLE (-4300 9900);
FORCEADD RESISTOR..2
(-8650 10650);
FORCEPROP 1 LAST $LOCATION R306
J 0
(-8600 10500);
DISPLAY 1.212766 (-8600 10500);
PAINT GREEN (-8600 10500);
FORCEPROP 0 LAST CDS_LOCATION R306
J 0
(-8600 10750);
DISPLAY 1.021277 (-8600 10750);
DISPLAY INVISIBLE (-8600 10750);
FORCEPROP 0 LAST $SEC 1
J 0
(-8600 10750);
DISPLAY 0.680851 (-8600 10750);
PAINT MONO (-8600 10750);
DISPLAY INVISIBLE (-8600 10750);
FORCEPROP 0 LAST CDS_SEC 1
J 0
(-8600 10750);
DISPLAY 1.021277 (-8600 10750);
DISPLAY INVISIBLE (-8600 10750);
FORCEPROP 0 LASTPIN (-8650 10750) $PN 1
R 1
J 0
(-8660 10760);
DISPLAY 0.680851 (-8660 10760);
PAINT MONO (-8660 10760);
FORCEPROP 0 LASTPIN (-8650 10500) $PN 2
R 1
J 2
(-8660 10490);
DISPLAY 0.680851 (-8660 10490);
PAINT MONO (-8660 10490);
FORCEPROP 0 LAST PACKAGE 0402
J 0
(-8600 10800);
DISPLAY 1.021277 (-8600 10800);
FORCEPROP 1 LAST VALUE 4.7KOHM
J 0
(-8600 10700);
DISPLAY 0.978723 (-8600 10700);
PAINT GREEN (-8600 10700);
FORCEPROP 0 LAST NO_ASSY TRUE
J 0
(-8600 10600);
DISPLAY 0.808511 (-8600 10600);
DISPLAY BOTH (-8600 10600);
FORCEPROP 1 LAST PATH I55
J 0
(-8847 10755);
DISPLAY 1.212766 (-8847 10755);
PAINT GREEN (-8847 10755);
DISPLAY INVISIBLE (-8847 10755);
FORCEPROP 1 LAST TOLERANCE 1%
J 0
(-8847 10905);
DISPLAY 1.212766 (-8847 10905);
PAINT GREEN (-8847 10905);
DISPLAY INVISIBLE (-8847 10905);
FORCEPROP 2 LAST CDS_LIB passive
J 0
(-8650 10650);
DISPLAY INVISIBLE (-8650 10650);
FORCEPROP 1 LAST CDS_LMAN_SYM_OUTLINE -50,50,50,-100
J 0
(-8650 10650);
DISPLAY 0.468085 (-8650 10650);
PAINT GREEN (-8650 10650);
DISPLAY INVISIBLE (-8650 10650);
FORCEPROP 1 LAST CLS_PN G155-14701-01
J 0
(-8786 10850);
DISPLAY 1.212766 (-8786 10850);
PAINT GREEN (-8786 10850);
DISPLAY INVISIBLE (-8786 10850);
FORCEADD VCC..1
(-2650 9050);
FORCEPROP 3 LASTPIN (-2600 9000) SIG_NAME XP3R3V_FPGA\g
J 0
(-2590 9010);
DISPLAY 0.659574 (-2590 9010);
PAINT MONO (-2590 9010);
DISPLAY INVISIBLE (-2590 9010);
FORCEPROP 1 LAST HDL_POWER XP3R3V_FPGA
J 1
(-2595 9105);
DISPLAY 1.021277 (-2595 9105);
PAINT GREEN (-2595 9105);
FORCEPROP 0 LAST VOLTAGE 3.3V
J 0
(-2900 9200);
DISPLAY 1.021277 (-2900 9200);
DISPLAY BOTH (-2900 9200);
FORCEPROP 1 LAST CDS_LMAN_SYM_OUTLINE -250,250,250,-250
J 0
(-2650 9050);
DISPLAY 0.468085 (-2650 9050);
PAINT GREEN (-2650 9050);
DISPLAY INVISIBLE (-2650 9050);
FORCEPROP 2 LAST CDS_LIB cls
J 0
(-2650 9050);
DISPLAY INVISIBLE (-2650 9050);
FORCEPROP 1 LAST BODY_TYPE PLUMBING
J 0
(-2695 9007);
DISPLAY 0.340426 (-2695 9007);
PAINT GREEN (-2695 9007);
DISPLAY INVISIBLE (-2695 9007);
FORCEPROP 1 LAST PATH I57
J 0
(-2615 9140);
DISPLAY 0.808511 (-2615 9140);
PAINT GREEN (-2615 9140);
DISPLAY INVISIBLE (-2615 9140);
FORCEADD RESISTOR..2
(-11500 10700);
FORCEPROP 1 LAST $LOCATION R74
J 0
(-11450 10550);
DISPLAY 1.212766 (-11450 10550);
PAINT GREEN (-11450 10550);
FORCEPROP 0 LAST CDS_LOCATION R74
J 0
(-11450 10800);
DISPLAY 1.021277 (-11450 10800);
DISPLAY INVISIBLE (-11450 10800);
FORCEPROP 0 LAST $SEC 1
J 0
(-11450 10800);
DISPLAY 0.680851 (-11450 10800);
PAINT MONO (-11450 10800);
DISPLAY INVISIBLE (-11450 10800);
FORCEPROP 0 LAST CDS_SEC 1
J 0
(-11450 10800);
DISPLAY 1.021277 (-11450 10800);
DISPLAY INVISIBLE (-11450 10800);
FORCEPROP 0 LASTPIN (-11500 10800) $PN 1
R 1
J 0
(-11510 10810);
DISPLAY 0.680851 (-11510 10810);
PAINT MONO (-11510 10810);
FORCEPROP 0 LASTPIN (-11500 10550) $PN 2
R 1
J 2
(-11510 10540);
DISPLAY 0.680851 (-11510 10540);
PAINT MONO (-11510 10540);
FORCEPROP 1 LAST VALUE 4.7KOHM
J 0
(-11450 10750);
DISPLAY 0.978723 (-11450 10750);
PAINT GREEN (-11450 10750);
FORCEPROP 0 LAST PACKAGE 0402
J 0
(-11450 10850);
DISPLAY 1.021277 (-11450 10850);
FORCEPROP 1 LAST PATH I6
J 0
(-11697 10805);
DISPLAY 1.212766 (-11697 10805);
PAINT GREEN (-11697 10805);
DISPLAY INVISIBLE (-11697 10805);
FORCEPROP 1 LAST TOLERANCE 1%
J 0
(-11697 10955);
DISPLAY 1.212766 (-11697 10955);
PAINT GREEN (-11697 10955);
DISPLAY INVISIBLE (-11697 10955);
FORCEPROP 1 LAST CDS_LMAN_SYM_OUTLINE -50,50,50,-100
J 0
(-11500 10700);
DISPLAY 0.468085 (-11500 10700);
PAINT GREEN (-11500 10700);
DISPLAY INVISIBLE (-11500 10700);
FORCEPROP 2 LAST CDS_LIB passive
J 0
(-11500 10700);
DISPLAY INVISIBLE (-11500 10700);
FORCEPROP 1 LAST CLS_PN G155-14701-01
J 0
(-11636 10900);
DISPLAY 1.212766 (-11636 10900);
PAINT GREEN (-11636 10900);
DISPLAY INVISIBLE (-11636 10900);
FORCEADD TP_PIONT..1
R 2
(-7850 9200);
FORCEPROP 1 LAST $LOCATION TP61
J 2
(-7900 9200);
DISPLAY 0.808511 (-7900 9200);
PAINT GREEN (-7900 9200);
FORCEPROP 0 LAST CDS_LOCATION TP61
J 0
(-7900 9250);
DISPLAY 1.021277 (-7900 9250);
DISPLAY INVISIBLE (-7900 9250);
FORCEPROP 0 LAST $SEC 1
J 0
(-7900 9250);
DISPLAY 0.680851 (-7900 9250);
PAINT MONO (-7900 9250);
DISPLAY INVISIBLE (-7900 9250);
FORCEPROP 0 LAST CDS_SEC 1
J 0
(-7900 9250);
DISPLAY 1.021277 (-7900 9250);
DISPLAY INVISIBLE (-7900 9250);
FORCEPROP 0 LASTPIN (-7750 9200) $PN 1
J 0
(-7740 9210);
DISPLAY 0.680851 (-7740 9210);
PAINT MONO (-7740 9210);
FORCEPROP 1 LAST PATH I63
J 2
(-7930 9313);
DISPLAY 0.808511 (-7930 9313);
PAINT GREEN (-7930 9313);
DISPLAY INVISIBLE (-7930 9313);
FORCEPROP 1 LAST JEDEC_TYPE TP010CT020B030_PTH
J 2
(-7726 9300);
DISPLAY 0.000000 (-7726 9300);
PAINT GREEN (-7726 9300);
DISPLAY INVISIBLE (-7726 9300);
FORCEPROP 1 LAST BOM_IGNORE TRUE
J 2
(-7726 9300);
DISPLAY 0.000000 (-7726 9300);
PAINT GREEN (-7726 9300);
DISPLAY INVISIBLE (-7726 9300);
FORCEPROP 1 LAST CDS_LMAN_SYM_OUTLINE -50,50,50,-50
J 2
(-7850 9200);
DISPLAY 0.468085 (-7850 9200);
PAINT GREEN (-7850 9200);
DISPLAY INVISIBLE (-7850 9200);
FORCEPROP 2 LAST CDS_LIB cls
J 0
(-7850 9200);
DISPLAY INVISIBLE (-7850 9200);
FORCEADD RESISTOR..1
(-3850 8350);
FORCEPROP 1 LAST $LOCATION R330
J 2
(-4050 8350);
DISPLAY 1.212766 (-4050 8350);
PAINT GREEN (-4050 8350);
FORCEPROP 0 LAST CDS_LOCATION R330
J 0
(-3650 8450);
DISPLAY 1.021277 (-3650 8450);
DISPLAY INVISIBLE (-3650 8450);
FORCEPROP 0 LAST $SEC 1
J 0
(-3650 8450);
DISPLAY 0.680851 (-3650 8450);
PAINT MONO (-3650 8450);
DISPLAY INVISIBLE (-3650 8450);
FORCEPROP 0 LAST CDS_SEC 1
J 0
(-3650 8450);
DISPLAY 1.021277 (-3650 8450);
DISPLAY INVISIBLE (-3650 8450);
FORCEPROP 0 LASTPIN (-3950 8350) $PN 1
J 2
(-3960 8360);
DISPLAY 0.680851 (-3960 8360);
PAINT MONO (-3960 8360);
FORCEPROP 0 LASTPIN (-3700 8350) $PN 2
J 0
(-3690 8360);
DISPLAY 0.680851 (-3690 8360);
PAINT MONO (-3690 8360);
FORCEPROP 1 LAST VALUE 33OHM
J 0
(-3550 8350);
DISPLAY 1.234043 (-3550 8350);
PAINT GREEN (-3550 8350);
FORCEPROP 0 LAST PACKAGE 0402
J 0
(-3900 8400);
DISPLAY 1.021277 (-3900 8400);
FORCEPROP 1 LAST PATH I64
J 0
(-4047 8455);
DISPLAY 1.212766 (-4047 8455);
PAINT GREEN (-4047 8455);
DISPLAY INVISIBLE (-4047 8455);
FORCEPROP 1 LAST TOLERANCE 1%
J 0
(-4047 8605);
DISPLAY 1.212766 (-4047 8605);
PAINT GREEN (-4047 8605);
DISPLAY INVISIBLE (-4047 8605);
FORCEPROP 1 LAST CLS_PN G155-133R0-01
J 0
(-3986 8550);
DISPLAY 1.212766 (-3986 8550);
PAINT GREEN (-3986 8550);
DISPLAY INVISIBLE (-3986 8550);
FORCEPROP 1 LAST CDS_LMAN_SYM_OUTLINE -50,50,100,-50
J 0
(-3850 8350);
DISPLAY 0.468085 (-3850 8350);
PAINT GREEN (-3850 8350);
DISPLAY INVISIBLE (-3850 8350);
FORCEPROP 2 LAST CDS_LIB passive
J 0
(-3850 8350);
DISPLAY INVISIBLE (-3850 8350);
FORCEPROP 2 LAST SIGNAL_MODEL DEFAULT_RESISTOR_33OHM_2_1
J 0
(-4000 8550);
DISPLAY 1.021277 (-4000 8550);
DISPLAY INVISIBLE (-4000 8550);
FORCEADD RESISTOR..1
R 5
(-3100 8700);
FORCEPROP 1 LAST $LOCATION R341
J 2
(-2850 8600);
DISPLAY 1.212766 (-2850 8600);
PAINT GREEN (-2850 8600);
FORCEPROP 0 LAST CDS_LOCATION R341
J 0
(-3050 8800);
DISPLAY 1.021277 (-3050 8800);
DISPLAY INVISIBLE (-3050 8800);
FORCEPROP 0 LAST $SEC 1
J 0
(-3050 8800);
DISPLAY 0.680851 (-3050 8800);
PAINT MONO (-3050 8800);
DISPLAY INVISIBLE (-3050 8800);
FORCEPROP 0 LAST CDS_SEC 1
J 0
(-3050 8800);
DISPLAY 1.021277 (-3050 8800);
DISPLAY INVISIBLE (-3050 8800);
FORCEPROP 0 LASTPIN (-3100 8800) $PN 1
R 1
J 0
(-3110 8810);
DISPLAY 0.680851 (-3110 8810);
PAINT MONO (-3110 8810);
FORCEPROP 0 LASTPIN (-3100 8550) $PN 2
R 1
J 2
(-3110 8540);
DISPLAY 0.680851 (-3110 8540);
PAINT MONO (-3110 8540);
FORCEPROP 0 LAST PACKAGE 0402
J 0
(-3050 8800);
DISPLAY 1.021277 (-3050 8800);
FORCEPROP 1 LAST VALUE 4.7KOHM
J 0
(-3050 8700);
DISPLAY 1.234043 (-3050 8700);
PAINT GREEN (-3050 8700);
FORCEPROP 1 LAST PATH I65
R 3
J 0
(-2995 8897);
DISPLAY 1.212766 (-2995 8897);
PAINT GREEN (-2995 8897);
DISPLAY INVISIBLE (-2995 8897);
FORCEPROP 1 LAST TOLERANCE 1%
R 3
J 0
(-2845 8897);
DISPLAY 1.212766 (-2845 8897);
PAINT GREEN (-2845 8897);
DISPLAY INVISIBLE (-2845 8897);
FORCEPROP 2 LAST CDS_LIB passive
J 0
(-3100 8700);
DISPLAY INVISIBLE (-3100 8700);
FORCEPROP 1 LAST CDS_LMAN_SYM_OUTLINE -50,50,100,-50
R 3
J 0
(-3100 8700);
DISPLAY 0.468085 (-3100 8700);
PAINT GREEN (-3100 8700);
DISPLAY INVISIBLE (-3100 8700);
FORCEPROP 1 LAST CLS_PN G155-14701-01
R 3
J 0
(-2900 8836);
DISPLAY 1.212766 (-2900 8836);
PAINT GREEN (-2900 8836);
DISPLAY INVISIBLE (-2900 8836);
FORCEADD RESISTOR..1
R 5
(-2600 8700);
FORCEPROP 1 LAST $LOCATION R342
J 2
(-2350 8600);
DISPLAY 1.212766 (-2350 8600);
PAINT GREEN (-2350 8600);
FORCEPROP 0 LAST CDS_LOCATION R342
J 0
(-2550 8800);
DISPLAY 1.021277 (-2550 8800);
DISPLAY INVISIBLE (-2550 8800);
FORCEPROP 0 LAST $SEC 1
J 0
(-2550 8800);
DISPLAY 0.680851 (-2550 8800);
PAINT MONO (-2550 8800);
DISPLAY INVISIBLE (-2550 8800);
FORCEPROP 0 LAST CDS_SEC 1
J 0
(-2550 8800);
DISPLAY 1.021277 (-2550 8800);
DISPLAY INVISIBLE (-2550 8800);
FORCEPROP 0 LASTPIN (-2600 8800) $PN 1
R 1
J 0
(-2610 8810);
DISPLAY 0.680851 (-2610 8810);
PAINT MONO (-2610 8810);
FORCEPROP 0 LASTPIN (-2600 8550) $PN 2
R 1
J 2
(-2610 8540);
DISPLAY 0.680851 (-2610 8540);
PAINT MONO (-2610 8540);
FORCEPROP 0 LAST PACKAGE 0402
J 0
(-2550 8800);
DISPLAY 1.021277 (-2550 8800);
FORCEPROP 1 LAST VALUE 4.7KOHM
J 0
(-2550 8700);
DISPLAY 1.234043 (-2550 8700);
PAINT GREEN (-2550 8700);
FORCEPROP 1 LAST CLS_PN G155-14701-01
R 3
J 0
(-2400 8836);
DISPLAY 1.212766 (-2400 8836);
PAINT GREEN (-2400 8836);
DISPLAY INVISIBLE (-2400 8836);
FORCEPROP 1 LAST CDS_LMAN_SYM_OUTLINE -50,50,100,-50
R 3
J 0
(-2600 8700);
DISPLAY 0.468085 (-2600 8700);
PAINT GREEN (-2600 8700);
DISPLAY INVISIBLE (-2600 8700);
FORCEPROP 2 LAST CDS_LIB passive
J 0
(-2600 8700);
DISPLAY INVISIBLE (-2600 8700);
FORCEPROP 1 LAST TOLERANCE 1%
R 3
J 0
(-2345 8897);
DISPLAY 1.212766 (-2345 8897);
PAINT GREEN (-2345 8897);
DISPLAY INVISIBLE (-2345 8897);
FORCEPROP 1 LAST PATH I66
R 3
J 0
(-2495 8897);
DISPLAY 1.212766 (-2495 8897);
PAINT GREEN (-2495 8897);
DISPLAY INVISIBLE (-2495 8897);
FORCEADD RESISTOR..1
(-3850 8250);
FORCEPROP 1 LAST $LOCATION R363
J 2
(-4050 8250);
DISPLAY 1.212766 (-4050 8250);
PAINT GREEN (-4050 8250);
FORCEPROP 0 LAST CDS_LOCATION R363
J 0
(-3650 8350);
DISPLAY 1.021277 (-3650 8350);
DISPLAY INVISIBLE (-3650 8350);
FORCEPROP 0 LAST $SEC 1
J 0
(-3650 8350);
DISPLAY 0.680851 (-3650 8350);
PAINT MONO (-3650 8350);
DISPLAY INVISIBLE (-3650 8350);
FORCEPROP 0 LAST CDS_SEC 1
J 0
(-3650 8350);
DISPLAY 1.021277 (-3650 8350);
DISPLAY INVISIBLE (-3650 8350);
FORCEPROP 0 LASTPIN (-3950 8250) $PN 1
J 2
(-3960 8260);
DISPLAY 0.680851 (-3960 8260);
PAINT MONO (-3960 8260);
FORCEPROP 0 LASTPIN (-3700 8250) $PN 2
J 0
(-3690 8260);
DISPLAY 0.680851 (-3690 8260);
PAINT MONO (-3690 8260);
FORCEPROP 0 LAST PACKAGE 0402
J 0
(-3900 8150);
DISPLAY 1.021277 (-3900 8150);
FORCEPROP 1 LAST VALUE 33OHM
J 0
(-3550 8250);
DISPLAY 1.234043 (-3550 8250);
PAINT GREEN (-3550 8250);
FORCEPROP 1 LAST PATH I67
J 0
(-4047 8355);
DISPLAY 1.212766 (-4047 8355);
PAINT GREEN (-4047 8355);
DISPLAY INVISIBLE (-4047 8355);
FORCEPROP 1 LAST TOLERANCE 1%
J 0
(-4047 8505);
DISPLAY 1.212766 (-4047 8505);
PAINT GREEN (-4047 8505);
DISPLAY INVISIBLE (-4047 8505);
FORCEPROP 1 LAST CLS_PN G155-133R0-01
J 0
(-3986 8450);
DISPLAY 1.212766 (-3986 8450);
PAINT GREEN (-3986 8450);
DISPLAY INVISIBLE (-3986 8450);
FORCEPROP 2 LAST CDS_LIB passive
J 0
(-3850 8250);
DISPLAY INVISIBLE (-3850 8250);
FORCEPROP 1 LAST CDS_LMAN_SYM_OUTLINE -50,50,100,-50
J 0
(-3850 8250);
DISPLAY 0.468085 (-3850 8250);
PAINT GREEN (-3850 8250);
DISPLAY INVISIBLE (-3850 8250);
FORCEPROP 2 LAST SIGNAL_MODEL DEFAULT_RESISTOR_33OHM_2_1
J 0
(-4000 8450);
DISPLAY 1.021277 (-4000 8450);
DISPLAY INVISIBLE (-4000 8450);
FORCEADD RESISTOR..2
(-11100 10700);
FORCEPROP 1 LAST $LOCATION R75
J 0
(-11050 10550);
DISPLAY 1.212766 (-11050 10550);
PAINT GREEN (-11050 10550);
FORCEPROP 0 LAST CDS_LOCATION R75
J 0
(-11050 10800);
DISPLAY 1.021277 (-11050 10800);
DISPLAY INVISIBLE (-11050 10800);
FORCEPROP 0 LAST $SEC 1
J 0
(-11050 10800);
DISPLAY 0.680851 (-11050 10800);
PAINT MONO (-11050 10800);
DISPLAY INVISIBLE (-11050 10800);
FORCEPROP 0 LAST CDS_SEC 1
J 0
(-11050 10800);
DISPLAY 1.021277 (-11050 10800);
DISPLAY INVISIBLE (-11050 10800);
FORCEPROP 0 LASTPIN (-11100 10800) $PN 1
R 1
J 0
(-11110 10810);
DISPLAY 0.680851 (-11110 10810);
PAINT MONO (-11110 10810);
FORCEPROP 0 LASTPIN (-11100 10550) $PN 2
R 1
J 2
(-11110 10540);
DISPLAY 0.680851 (-11110 10540);
PAINT MONO (-11110 10540);
FORCEPROP 1 LAST VALUE 4.7KOHM
J 0
(-11050 10750);
DISPLAY 0.978723 (-11050 10750);
PAINT GREEN (-11050 10750);
FORCEPROP 0 LAST PACKAGE 0402
J 0
(-11050 10850);
DISPLAY 1.021277 (-11050 10850);
FORCEPROP 1 LAST PATH I7
J 0
(-11297 10805);
DISPLAY 1.212766 (-11297 10805);
PAINT GREEN (-11297 10805);
DISPLAY INVISIBLE (-11297 10805);
FORCEPROP 1 LAST TOLERANCE 1%
J 0
(-11297 10955);
DISPLAY 1.212766 (-11297 10955);
PAINT GREEN (-11297 10955);
DISPLAY INVISIBLE (-11297 10955);
FORCEPROP 1 LAST CLS_PN G155-14701-01
J 0
(-11236 10900);
DISPLAY 1.212766 (-11236 10900);
PAINT GREEN (-11236 10900);
DISPLAY INVISIBLE (-11236 10900);
FORCEPROP 2 LAST CDS_LIB passive
J 0
(-11100 10700);
DISPLAY INVISIBLE (-11100 10700);
FORCEPROP 1 LAST CDS_LMAN_SYM_OUTLINE -50,50,50,-100
J 0
(-11100 10700);
DISPLAY 0.468085 (-11100 10700);
PAINT GREEN (-11100 10700);
DISPLAY INVISIBLE (-11100 10700);
FORCEADD RESISTOR..2
(-5150 10200);
FORCEPROP 1 LAST $LOCATION R168
J 0
(-5100 10100);
DISPLAY 1.212766 (-5100 10100);
PAINT GREEN (-5100 10100);
FORCEPROP 0 LAST CDS_LOCATION R168
J 0
(-5100 10300);
DISPLAY 1.021277 (-5100 10300);
DISPLAY INVISIBLE (-5100 10300);
FORCEPROP 0 LAST $SEC 1
J 0
(-5100 10300);
DISPLAY 0.680851 (-5100 10300);
PAINT MONO (-5100 10300);
DISPLAY INVISIBLE (-5100 10300);
FORCEPROP 0 LAST CDS_SEC 1
J 0
(-5100 10300);
DISPLAY 1.021277 (-5100 10300);
DISPLAY INVISIBLE (-5100 10300);
FORCEPROP 0 LASTPIN (-5150 10300) $PN 1
R 1
J 0
(-5160 10310);
DISPLAY 0.680851 (-5160 10310);
PAINT MONO (-5160 10310);
FORCEPROP 0 LASTPIN (-5150 10050) $PN 2
R 1
J 2
(-5160 10040);
DISPLAY 0.680851 (-5160 10040);
PAINT MONO (-5160 10040);
FORCEPROP 0 LAST PACKAGE 0402
J 0
(-5100 10250);
DISPLAY 1.021277 (-5100 10250);
FORCEPROP 1 LAST VALUE 1MOHM
J 0
(-5100 10000);
DISPLAY 1.212766 (-5100 10000);
PAINT GREEN (-5100 10000);
FORCEPROP 0 LAST NO_ASSY TRUE
R 1
J 0
(-5200 9950);
DISPLAY 0.808511 (-5200 9950);
DISPLAY BOTH (-5200 9950);
FORCEPROP 2 LAST CDS_LIB passive
J 0
(-5150 10200);
DISPLAY INVISIBLE (-5150 10200);
FORCEPROP 1 LAST PATH I70
J 0
(-5347 10305);
DISPLAY 1.212766 (-5347 10305);
PAINT GREEN (-5347 10305);
DISPLAY INVISIBLE (-5347 10305);
FORCEPROP 1 LAST CDS_LMAN_SYM_OUTLINE -50,50,50,-100
J 0
(-5150 10200);
DISPLAY 0.468085 (-5150 10200);
PAINT GREEN (-5150 10200);
DISPLAY INVISIBLE (-5150 10200);
FORCEPROP 1 LAST TOLERANCE 1%
J 0
(-5347 10455);
DISPLAY 1.212766 (-5347 10455);
PAINT GREEN (-5347 10455);
DISPLAY INVISIBLE (-5347 10455);
FORCEPROP 1 LAST CLS_PN G155-11004-01
J 0
(-5286 10400);
DISPLAY 1.212766 (-5286 10400);
PAINT GREEN (-5286 10400);
DISPLAY INVISIBLE (-5286 10400);
FORCEADD TP_PIONT..1
(-1550 8350);
FORCEPROP 1 LAST $LOCATION TP1
J 0
(-1450 8350);
DISPLAY 0.808511 (-1450 8350);
PAINT GREEN (-1450 8350);
FORCEPROP 0 LAST CDS_LOCATION TP1
J 0
(-1450 8400);
DISPLAY 1.021277 (-1450 8400);
DISPLAY INVISIBLE (-1450 8400);
FORCEPROP 0 LAST $SEC 1
J 0
(-1450 8400);
DISPLAY 0.680851 (-1450 8400);
PAINT MONO (-1450 8400);
DISPLAY INVISIBLE (-1450 8400);
FORCEPROP 0 LAST CDS_SEC 1
J 0
(-1450 8400);
DISPLAY 1.021277 (-1450 8400);
DISPLAY INVISIBLE (-1450 8400);
FORCEPROP 0 LASTPIN (-1650 8350) $PN 1
J 2
(-1660 8360);
DISPLAY 0.680851 (-1660 8360);
PAINT MONO (-1660 8360);
FORCEPROP 2 LAST CDS_LIB cls
J 0
(-1550 8350);
DISPLAY INVISIBLE (-1550 8350);
FORCEPROP 1 LAST PATH I71
J 0
(-1470 8463);
DISPLAY 0.808511 (-1470 8463);
PAINT GREEN (-1470 8463);
DISPLAY INVISIBLE (-1470 8463);
FORCEPROP 1 LAST CDS_LMAN_SYM_OUTLINE -50,50,50,-50
J 0
(-1550 8350);
DISPLAY 0.468085 (-1550 8350);
PAINT GREEN (-1550 8350);
DISPLAY INVISIBLE (-1550 8350);
FORCEPROP 1 LAST BOM_IGNORE TRUE
J 0
(-1674 8450);
DISPLAY 0.000000 (-1674 8450);
PAINT GREEN (-1674 8450);
DISPLAY INVISIBLE (-1674 8450);
FORCEPROP 1 LAST JEDEC_TYPE TP010CT020B030_PTH
J 0
(-1674 8450);
DISPLAY 0.000000 (-1674 8450);
PAINT GREEN (-1674 8450);
DISPLAY INVISIBLE (-1674 8450);
FORCEADD TP_PIONT..1
(-1550 8250);
FORCEPROP 1 LAST $LOCATION TP2
J 0
(-1450 8250);
DISPLAY 0.808511 (-1450 8250);
PAINT GREEN (-1450 8250);
FORCEPROP 0 LAST CDS_LOCATION TP2
J 0
(-1450 8300);
DISPLAY 1.021277 (-1450 8300);
DISPLAY INVISIBLE (-1450 8300);
FORCEPROP 0 LAST $SEC 1
J 0
(-1450 8300);
DISPLAY 0.680851 (-1450 8300);
PAINT MONO (-1450 8300);
DISPLAY INVISIBLE (-1450 8300);
FORCEPROP 0 LAST CDS_SEC 1
J 0
(-1450 8300);
DISPLAY 1.021277 (-1450 8300);
DISPLAY INVISIBLE (-1450 8300);
FORCEPROP 0 LASTPIN (-1650 8250) $PN 1
J 2
(-1660 8260);
DISPLAY 0.680851 (-1660 8260);
PAINT MONO (-1660 8260);
FORCEPROP 2 LAST CDS_LIB cls
J 0
(-1550 8250);
DISPLAY INVISIBLE (-1550 8250);
FORCEPROP 1 LAST PATH I72
J 0
(-1470 8363);
DISPLAY 0.808511 (-1470 8363);
PAINT GREEN (-1470 8363);
DISPLAY INVISIBLE (-1470 8363);
FORCEPROP 1 LAST CDS_LMAN_SYM_OUTLINE -50,50,50,-50
J 0
(-1550 8250);
DISPLAY 0.468085 (-1550 8250);
PAINT GREEN (-1550 8250);
DISPLAY INVISIBLE (-1550 8250);
FORCEPROP 1 LAST BOM_IGNORE TRUE
J 0
(-1674 8350);
DISPLAY 0.000000 (-1674 8350);
PAINT GREEN (-1674 8350);
DISPLAY INVISIBLE (-1674 8350);
FORCEPROP 1 LAST JEDEC_TYPE TP010CT020B030_PTH
J 0
(-1674 8350);
DISPLAY 0.000000 (-1674 8350);
PAINT GREEN (-1674 8350);
DISPLAY INVISIBLE (-1674 8350);
FORCEADD OFFPAGE_IN..1
(-9750 9500);
FORCEPROP 1 LAST OFFPAGE TRUE
J 0
(-9740 9555);
DISPLAY 0.808511 (-9740 9555);
PAINT GREEN (-9740 9555);
DISPLAY INVISIBLE (-9740 9555);
FORCEPROP 1 LAST BODY_TYPE COMMENT
J 0
(-9740 9635);
DISPLAY 0.808511 (-9740 9635);
PAINT GREEN (-9740 9635);
DISPLAY INVISIBLE (-9740 9635);
FORCEPROP 1 LAST CDS_LMAN_SYM_OUTLINE -50,50,50,-50
J 0
(-9750 9500);
DISPLAY 0.468085 (-9750 9500);
PAINT GREEN (-9750 9500);
DISPLAY INVISIBLE (-9750 9500);
FORCEPROP 2 LAST PATH I74
J 0
(-9700 9600);
DISPLAY 1.021277 (-9700 9600);
DISPLAY INVISIBLE (-9700 9600);
FORCEPROP 2 LAST CDS_LIB cls
J 0
(-9750 9500);
DISPLAY INVISIBLE (-9750 9500);
FORCEPROP 2 LAST $XR0 25C6<> 
J 0
(-9964 9500);
DISPLAY 0.638298 (-9964 9500);
PAINT MONO (-9964 9500);
FORCEADD OFFPAGE_OUT..1
R 2
(-9750 9600);
FORCEPROP 1 LAST BODY_TYPE COMMENT
J 2
(-9760 9735);
DISPLAY 0.808511 (-9760 9735);
PAINT GREEN (-9760 9735);
DISPLAY INVISIBLE (-9760 9735);
FORCEPROP 1 LAST OFFPAGE TRUE
J 2
(-9760 9655);
DISPLAY 0.808511 (-9760 9655);
PAINT GREEN (-9760 9655);
DISPLAY INVISIBLE (-9760 9655);
FORCEPROP 1 LAST CDS_LMAN_SYM_OUTLINE -50,50,50,-50
J 2
(-9750 9600);
DISPLAY 0.468085 (-9750 9600);
PAINT GREEN (-9750 9600);
DISPLAY INVISIBLE (-9750 9600);
FORCEPROP 2 LAST PATH I75
J 0
(-9700 9700);
DISPLAY 1.021277 (-9700 9700);
DISPLAY INVISIBLE (-9700 9700);
FORCEPROP 2 LAST CDS_LIB cls
J 0
(-9750 9600);
DISPLAY INVISIBLE (-9750 9600);
FORCEPROP 2 LAST $XR0 25C6<> 
J 0
(-9964 9600);
DISPLAY 0.638298 (-9964 9600);
PAINT MONO (-9964 9600);
FORCEADD OFFPAGE_IN..1
(-4400 9600);
FORCEPROP 2 LAST CDS_LIB cls
J 0
(-4400 9600);
DISPLAY INVISIBLE (-4400 9600);
FORCEPROP 2 LAST PATH I76
J 0
(-4350 9700);
DISPLAY 1.021277 (-4350 9700);
DISPLAY INVISIBLE (-4350 9700);
FORCEPROP 1 LAST CDS_LMAN_SYM_OUTLINE -50,50,50,-50
J 0
(-4400 9600);
DISPLAY 0.468085 (-4400 9600);
PAINT GREEN (-4400 9600);
DISPLAY INVISIBLE (-4400 9600);
FORCEPROP 1 LAST BODY_TYPE COMMENT
J 0
(-4390 9735);
DISPLAY 0.808511 (-4390 9735);
PAINT GREEN (-4390 9735);
DISPLAY INVISIBLE (-4390 9735);
FORCEPROP 1 LAST OFFPAGE TRUE
J 0
(-4390 9655);
DISPLAY 0.808511 (-4390 9655);
PAINT GREEN (-4390 9655);
DISPLAY INVISIBLE (-4390 9655);
FORCEPROP 2 LAST $XR0 25C6<> 
J 0
(-4614 9600);
DISPLAY 0.638298 (-4614 9600);
PAINT MONO (-4614 9600);
FORCEADD SHEET_A1..1
(950 3700);
FORCEPROP 2 LAST CUSTOM_TXT_CDS <XR_PAGE_TITLE>
J 0
(-14620 15050);
DISPLAY 0.638298 (-14620 15050);
PAINT PINK (-14620 15050);
FORCEPROP 1 LAST CUSTOM_TXT_CDS <DOCNO>
J 0
(-1100 4085);
DISPLAY 0.978723 (-1100 4085);
FORCEPROP 1 LAST CUSTOM_TXT_CDS <CON_PAGE_NUM>
J 0
(-1205 3750);
DISPLAY 0.978723 (-1205 3750);
FORCEPROP 1 LAST CUSTOM_TXT_CDS <DATE>
J 0
(250 3875);
DISPLAY 0.978723 (250 3875);
FORCEPROP 1 LAST CUSTOM_TXT_CDS <TITLE>
J 1
(-835 4330);
DISPLAY 0.978723 (-835 4330);
FORCEPROP 1 LAST CUSTOM_TXT_CDS <DESIGNER>
J 0
(250 4300);
DISPLAY 0.978723 (250 4300);
FORCEPROP 1 LAST CUSTOM_TXT_CDS <CON_TOTAL_PAGES>
J 0
(-895 3750);
DISPLAY 0.808511 (-895 3750);
FORCEPROP 1 LAST CUSTOM_TXT_CDS <ASSY_PN>
J 0
(-1100 3875);
DISPLAY 0.978723 (-1100 3875);
FORCEPROP 1 LAST CUSTOM_TXT_CDS <DOCREV>
J 0
(250 4075);
DISPLAY 0.978723 (250 4075);
FORCEPROP 1 LAST TITLE VIBRATION_SENSOR
J 0
(-1550 4550);
DISPLAY 3.042553 (-1550 4550);
PAINT GREEN (-1550 4550);
FORCEPROP 1 LAST COMMENT_BODY TRUE
J 0
(960 3755);
DISPLAY 0.808511 (960 3755);
DISPLAY INVISIBLE (960 3755);
FORCEPROP 2 LAST CDS_LIB cls
J 0
(950 3700);
DISPLAY INVISIBLE (950 3700);
FORCEPROP 1 LAST CDS_LMAN_SYM_OUTLINE -15850,11500,200,-200
J 0
(950 3700);
DISPLAY 0.468085 (950 3700);
PAINT GREEN (950 3700);
DISPLAY INVISIBLE (950 3700);
FORCEPROP 2 LAST PAGE_BORDER TRUE
J 0
(-14620 15050);
DISPLAY 0.638298 (-14620 15050);
PAINT PINK (-14620 15050);
DISPLAY INVISIBLE (-14620 15050);
FORCEPROP 2 LAST CDS_XR_PAGE_TITLE CR-20 : @TIMECARD_LIB.TIMECARD(SCH_1):PAGE20
J 0
(-14620 15050);
DISPLAY 0.638298 (-14620 15050);
PAINT PINK (-14620 15050);
DISPLAY INVISIBLE (-14620 15050);
WIRE 16 -1 (-7800 10300)(-7600 10300);
WIRE 16 -1 (-7800 10400)(-7800 10300);
WIRE 16 -1 (-7800 10400)(-7600 10400);
WIRE 16 -1 (-8000 10400)(-7800 10400);
WIRE 16 -1 (-8000 12000)(-8000 10400);
WIRE 16 -1 (-8750 12000)(-8000 12000);
FORCEPROP 2 LAST SIG_NAME VDD_BNO085
J 0
(-8560 12010);
DISPLAY 1.021277 (-8560 12010);
WIRE 16 -1 (-8750 11800)(-8750 12000);
WIRE 16 -1 (-9200 12000)(-8750 12000);
WIRE 16 -1 (-9550 12000)(-9200 12000);
WIRE 16 -1 (-9200 11800)(-9200 12000);
WIRE 16 -1 (-5650 10200)(-5300 10200);
WIRE 16 -1 (-5300 10200)(-5300 10450);
WIRE 16 -1 (-5150 10450)(-5300 10450);
WIRE 16 -1 (-4600 10450)(-5150 10450);
WIRE 16 -1 (-5150 10300)(-5150 10450);
WIRE 16 -1 (-4600 10400)(-4600 10450);
WIRE 16 -1 (-4400 10450)(-4600 10450);
WIRE 16 -1 (-5650 10100)(-5300 10100);
WIRE 16 -1 (-5300 10100)(-5300 9900);
WIRE 16 -1 (-5150 9900)(-5300 9900);
WIRE 16 -1 (-4600 9900)(-5150 9900);
WIRE 16 -1 (-5150 10050)(-5150 9900);
WIRE 16 -1 (-4400 9900)(-4600 9900);
WIRE 16 -1 (-4600 10000)(-4600 9900);
WIRE 16 -1 (-5400 10700)(-5400 10400);
WIRE 16 -1 (-5400 10700)(-4900 10700);
WIRE 16 -1 (-5400 10400)(-5650 10400);
WIRE 16 -1 (-7600 9200)(-7750 9200);
WIRE 16 -1 (-2300 9700)(-700 9700);
FORCEPROP 2 LAST SIG_NAME FPGA_OUT_BNO080_RST_N
J 0
(-1760 9710);
DISPLAY 1.021277 (-1760 9710);
WIRE 16 -1 (-3700 8250)(-2600 8250);
WIRE 16 -1 (-1650 8250)(-2600 8250);
FORCEPROP 2 LAST SIG_NAME BNO080_EVN_SCL
J 0
(-2410 8260);
DISPLAY 1.021277 (-2410 8260);
WIRE 16 -1 (-2600 8550)(-2600 8250);
WIRE 16 -1 (-10050 10000)(-7600 10000);
FORCEPROP 2 LAST SIG_NAME R_BNO080_I2C_SDA
J 0
(-8510 10010);
DISPLAY 1.021277 (-8510 10010);
WIRE 16 -1 (-10050 9900)(-7600 9900);
FORCEPROP 2 LAST SIG_NAME R_BNO080_I2C_SCL
J 0
(-8510 9910);
DISPLAY 1.021277 (-8510 9910);
WIRE 16 -1 (-7600 9300)(-8400 9300);
WIRE 16 -1 (-8400 9600)(-8400 9300);
WIRE 16 -1 (-8400 9300)(-8400 9150);
WIRE 16 -1 (-8650 9600)(-8400 9600);
WIRE 16 -1 (-8650 10500)(-8650 9600);
WIRE 16 -1 (-7600 9400)(-8750 9400);
WIRE 16 -1 (-8750 9400)(-8750 9150);
WIRE 16 -1 (-9100 9500)(-7600 9500);
WIRE 16 -1 (-9100 9150)(-9100 9500);
WIRE 16 -1 (-9700 9600)(-9600 9600);
WIRE 16 -1 (-9600 9800)(-9600 9600);
WIRE 16 -1 (-10050 9800)(-9600 9800);
WIRE 16 -1 (-9600 9800)(-7600 9800);
FORCEPROP 2 LAST SIG_NAME R_BNO080_INT_N
J 0
(-8510 9810);
DISPLAY 1.021277 (-8510 9810);
WIRE 16 -1 (-9700 9500)(-9550 9500);
WIRE 16 -1 (-9550 9700)(-9550 9500);
WIRE 16 -1 (-10050 9700)(-9550 9700);
WIRE 16 -1 (-9550 9700)(-9050 9700);
WIRE 16 -1 (-7600 9700)(-9050 9700);
FORCEPROP 2 LAST SIG_NAME R_BNO080_BOOT_N
J 0
(-8510 9710);
DISPLAY 1.021277 (-8510 9710);
WIRE 16 -1 (-9050 10500)(-9050 9700);
WIRE 16 -1 (-7600 10100)(-9450 10100);
FORCEPROP 2 LAST SIG_NAME BNO080_SA0
J 0
(-8510 10110);
DISPLAY 1.021277 (-8510 10110);
WIRE 16 -1 (-9450 10500)(-9450 10100);
WIRE 16 -1 (-9450 10100)(-9450 9150);
WIRE 16 -1 (-12950 9700)(-10300 9700);
FORCEPROP 2 LAST SIG_NAME FPGA_OUT_BNO080_BOOT_N
J 0
(-12860 9710);
DISPLAY 1.021277 (-12860 9710);
WIRE 16 -1 (-10700 10550)(-10700 9800);
WIRE 16 -1 (-10700 9800)(-10300 9800);
WIRE 16 -1 (-12950 9800)(-10700 9800);
FORCEPROP 2 LAST SIG_NAME FPGA_IN_BNO080_INT_N
J 0
(-12860 9810);
DISPLAY 1.021277 (-12860 9810);
WIRE 16 -1 (-10300 9900)(-11100 9900);
WIRE 16 -1 (-11100 10550)(-11100 9900);
WIRE 16 -1 (-12950 9900)(-11100 9900);
FORCEPROP 2 LAST SIG_NAME BNO080_I2C_SCL
J 0
(-12860 9910);
DISPLAY 1.021277 (-12860 9910);
WIRE 16 -1 (-10300 10000)(-11500 10000);
WIRE 16 -1 (-11500 10550)(-11500 10000);
WIRE 16 -1 (-12950 10000)(-11500 10000);
FORCEPROP 2 LAST SIG_NAME BNO080_I2C_SDA
J 0
(-12860 10010);
DISPLAY 1.021277 (-12860 10010);
WIRE 16 -1 (-1650 8350)(-3100 8350);
FORCEPROP 2 LAST SIG_NAME BNO080_EVN_SDA
J 0
(-2410 8360);
DISPLAY 1.021277 (-2410 8360);
WIRE 16 -1 (-3100 8550)(-3100 8350);
WIRE 16 -1 (-3100 8350)(-3700 8350);
WIRE 16 -1 (-5450 8250)(-3950 8250);
FORCEPROP 2 LAST SIG_NAME R_BNO080_EVN_SCL
J 0
(-5210 8260);
DISPLAY 1.021277 (-5210 8260);
WIRE 16 -1 (-5450 9900)(-5450 8250);
WIRE 16 -1 (-5650 9900)(-5450 9900);
WIRE 16 -1 (-5400 8350)(-3950 8350);
FORCEPROP 2 LAST SIG_NAME R_BNO080_EVN_SDA
J 0
(-5210 8360);
DISPLAY 1.021277 (-5210 8360);
WIRE 16 -1 (-5400 10000)(-5400 8350);
WIRE 16 -1 (-5650 10000)(-5400 10000);
WIRE 16 -1 (-2550 9700)(-3100 9700);
WIRE 16 -1 (-3100 9700)(-3100 10100);
WIRE 16 -1 (-4000 9700)(-3100 9700);
WIRE 16 -1 (-4000 9450)(-4000 9700);
WIRE 16 -1 (-4250 9700)(-4000 9700);
WIRE 16 -1 (-4250 9700)(-4250 9600);
WIRE 16 -1 (-5650 9700)(-4250 9700);
FORCEPROP 2 LAST SIG_NAME R_BNO080_RST_N
J 0
(-5010 9710);
DISPLAY 1.021277 (-5010 9710);
WIRE 16 -1 (-4250 9600)(-4350 9600);
WIRE 16 -1 (-3850 10450)(-3850 9900);
WIRE 16 -1 (-4150 10450)(-3850 10450);
WIRE 16 -1 (-3850 10550)(-3850 10450);
WIRE 16 -1 (-3850 9900)(-4150 9900);
WIRE 16 -1 (-3850 10700)(-3850 10550);
WIRE 16 -1 (-3850 10550)(-3600 10550);
WIRE 16 -1 (-3600 10550)(-3600 10400);
WIRE 16 -1 (-3850 10700)(-4650 10700);
WIRE 16 -1 (-8650 10950)(-8650 10750);
WIRE 16 -1 (-9050 10950)(-8650 10950);
WIRE 16 -1 (-9050 10950)(-9050 10750);
WIRE 16 -1 (-9450 10950)(-9050 10950);
WIRE 16 -1 (-9450 10750)(-9450 10950);
WIRE 16 -1 (-10700 10950)(-9450 10950);
WIRE 16 -1 (-10700 10800)(-10700 10950);
WIRE 16 -1 (-11100 10950)(-10700 10950);
WIRE 16 -1 (-11100 10800)(-11100 10950);
WIRE 16 -1 (-11100 10950)(-11500 10950);
WIRE 16 -1 (-11500 10800)(-11500 10950);
WIRE 16 -1 (-11500 11050)(-11500 10950);
WIRE 16 -1 (-10250 11550)(-10250 11300);
WIRE 16 -1 (-10250 11300)(-9200 11300);
WIRE 16 -1 (-9200 11300)(-8750 11300);
WIRE 16 -1 (-9200 11550)(-9200 11300);
WIRE 16 -1 (-8750 11250)(-8750 11300);
WIRE 16 -1 (-8750 11550)(-8750 11300);
WIRE 16 -1 (-9450 8900)(-9450 8550);
WIRE 16 -1 (-9450 8550)(-9100 8550);
WIRE 16 -1 (-9100 8900)(-9100 8550);
WIRE 16 -1 (-9100 8550)(-8750 8550);
WIRE 16 -1 (-8750 8550)(-8400 8550);
WIRE 16 -1 (-8750 8900)(-8750 8550);
WIRE 16 -1 (-7800 8550)(-8400 8550);
WIRE 16 -1 (-8400 8900)(-8400 8550);
WIRE 16 -1 (-7800 8550)(-7800 8900);
WIRE 16 -1 (-7800 8500)(-7800 8550);
WIRE 16 -1 (-7800 8900)(-7600 8900);
WIRE 16 -1 (-7800 8900)(-7800 9000);
WIRE 16 -1 (-7600 9000)(-7800 9000);
WIRE 16 -1 (-2600 8950)(-2600 9000);
WIRE 16 -1 (-2600 8950)(-2600 8800);
WIRE 16 -1 (-2600 8950)(-3100 8950);
WIRE 16 -1 (-3100 8800)(-3100 8950);
WIRE 16 -1 (-9950 12000)(-10250 12000);
WIRE 16 -1 (-10250 12000)(-10250 12150);
WIRE 16 -1 (-10250 11800)(-10250 12000);
WIRE 16 -1 (-4000 9000)(-4000 9200);
WIRE 16 -1 (-3100 10350)(-3100 10700);
DOT 1 (-4250 9700);
DOT 1 (-3100 9700);
DOT 1 (-2600 8950);
DOT 1 (-11100 10950);
DOT 1 (-5150 9900);
DOT 1 (-5150 10450);
DOT 1 (-4600 9900);
DOT 1 (-4600 10450);
DOT 1 (-3850 10450);
DOT 1 (-3850 10550);
DOT 1 (-4000 9700);
DOT 1 (-11500 10000);
DOT 1 (-11100 9900);
DOT 1 (-10700 9800);
DOT 1 (-11500 10950);
DOT 1 (-10700 10950);
DOT 1 (-9100 8550);
DOT 1 (-8750 8550);
DOT 1 (-9450 10100);
DOT 1 (-10250 12000);
DOT 1 (-9450 10950);
DOT 1 (-9200 11300);
DOT 1 (-9050 10950);
DOT 1 (-8750 11300);
DOT 1 (-9200 12000);
DOT 1 (-8750 12000);
DOT 1 (-8400 8550);
DOT 1 (-8400 9300);
DOT 1 (-7800 8550);
DOT 1 (-7800 8900);
DOT 1 (-7800 10400);
DOT 1 (-3100 8350);
DOT 1 (-2600 8250);
DOT 1 (-9050 9700);
DOT 1 (-9600 9800);
DOT 1 (-9550 9700);
FORCENOTE
VIBRATION_SENSOR
(-8850 14000) 0;
DISPLAY LEFT (-8850 14000);
DISPLAY 4.914894 (-8850 14000);
FORCENOTE
I2C ADDR = 0X4A. 
(-11550 9150) 0;
DISPLAY LEFT (-11550 9150);
DISPLAY 2.000000 (-11550 9150);
QUIT
